G04 ================== begin FILE IDENTIFICATION RECORD ==================*
G04 Layout Name:  x887571-005_osp.brd*
G04 Film Name:    outline*
G04 File Format:  Gerber RS274X*
G04 File Origin:  Cadence Allegro 16.3-S036*
G04 Origin Date:  Thu Jul 03 00:06:57 2014*
G04 *
G04 Layer:  DRAWING FORMAT/COMMON TEXT*
G04 Layer:  BOARD GEOMETRY/OUTLINE*
G04 Layer:  BOARD GEOMETRY/OUTLINE TEXT*
G04 *
G04 Offset:    (0.0000 0.0000)*
G04 Mirror:    No*
G04 Mode:      Positive*
G04 Rotation:  0*
G04 FullContactRelief:  No*
G04 UndefLineWidth:     4.0000*
G04 ================== end FILE IDENTIFICATION RECORD ====================*
%FSLAX25Y25*MOIN*%
%IR0*IPPOS*OFA0.00000B0.00000*MIA0B0*SFA1.00000B1.00000*%
%ADD10C,.01*%
%ADD11C,.012*%
%ADD12C,.013*%
%ADD13C,.015*%
%ADD14C,.004*%
%ADD15C,.005*%
%ADD16C,.006*%
%ADD17C,.007*%
%ADD18C,.008*%
G75*
%LPD*%
G75*
G54D10*
G01X-1184000Y-502500D02*
Y-512500D01*
G01X-1186683Y-502500D02*
X-1181317D01*
G01X-1176833Y-512500D02*
Y-502500D01*
X-1173917D01*
X-1172983Y-503000D01*
X-1172400Y-503667D01*
X-1172167Y-505000D01*
X-1172400Y-506333D01*
X-1173100Y-507167D01*
X-1173917Y-507667D01*
X-1176833D01*
G01X-1173917D02*
X-1172167Y-512500D01*
G01X-1167917D02*
X-1165000Y-502500D01*
X-1162083Y-512500D01*
G01X-1163133Y-509000D02*
X-1166867D01*
G01X-1155500Y-512500D02*
Y-508000D01*
X-1157833Y-502500D01*
G01X-1153167D02*
X-1155500Y-508000D01*
G01X-1135567Y-507167D02*
X-1135100Y-506667D01*
X-1134750Y-505834D01*
X-1134517Y-504667D01*
X-1134750Y-503667D01*
X-1135217Y-503000D01*
X-1136033Y-502500D01*
X-1139183D01*
Y-512500D01*
X-1135333D01*
X-1134517Y-511833D01*
X-1134050Y-510833D01*
X-1133817Y-509667D01*
X-1134050Y-508500D01*
X-1134750Y-507500D01*
X-1135567Y-507167D01*
X-1139183D01*
G01X-1129917Y-512500D02*
X-1127000Y-502500D01*
X-1124083Y-512500D01*
G01X-1125133Y-509000D02*
X-1128867D01*
G01X-1114933Y-503333D02*
X-1115633Y-502833D01*
X-1116450Y-502500D01*
X-1117383D01*
X-1118433Y-503000D01*
X-1119250Y-503833D01*
X-1119833Y-504833D01*
X-1120300Y-506500D01*
X-1120417Y-508000D01*
X-1120183Y-509500D01*
X-1119833Y-510500D01*
X-1119133Y-511500D01*
X-1118317Y-512167D01*
X-1117500Y-512500D01*
X-1116683D01*
X-1115867Y-512167D01*
X-1115167Y-511667D01*
X-1114583Y-511000D01*
G01X-1110567Y-512500D02*
Y-502500D01*
G01X-1106133D02*
X-1110567Y-508667D01*
G01X-1105433Y-512500D02*
X-1108583Y-505834D01*
G01X-1100833Y-512500D02*
Y-502500D01*
X-1098033D01*
X-1097100Y-503000D01*
X-1096400Y-504167D01*
X-1096167Y-505500D01*
X-1096400Y-506833D01*
X-1096983Y-507833D01*
X-1098033Y-508334D01*
X-1100833D01*
G01X-1091333Y-502500D02*
Y-512500D01*
X-1086667D01*
G01X-1082417D02*
X-1079500Y-502500D01*
X-1076583Y-512500D01*
G01X-1077633Y-509000D02*
X-1081367D01*
G01X-1072683Y-512500D02*
Y-502500D01*
X-1067317Y-512500D01*
Y-502500D01*
G01X-1058167Y-512500D02*
X-1062833D01*
Y-502500D01*
X-1058167D01*
G01X-1060033Y-507333D02*
X-1062833D01*
G01X-1043717Y-512500D02*
Y-502500D01*
X-1039283D01*
G01X-1040917Y-507333D02*
X-1043717D01*
G01X-1034917Y-512500D02*
X-1032000Y-502500D01*
X-1029083Y-512500D01*
G01X-1030133Y-509000D02*
X-1033867D01*
G01X-1021567Y-507167D02*
X-1021100Y-506667D01*
X-1020750Y-505834D01*
X-1020517Y-504667D01*
X-1020750Y-503667D01*
X-1021217Y-503000D01*
X-1022033Y-502500D01*
X-1025183D01*
Y-512500D01*
X-1021333D01*
X-1020517Y-511833D01*
X-1020050Y-510833D01*
X-1019817Y-509667D01*
X-1020050Y-508500D01*
X-1020750Y-507500D01*
X-1021567Y-507167D01*
X-1025183D01*
G01X-1002567D02*
X-1002100Y-506667D01*
X-1001750Y-505834D01*
X-1001517Y-504667D01*
X-1001750Y-503667D01*
X-1002217Y-503000D01*
X-1003033Y-502500D01*
X-1006183D01*
Y-512500D01*
X-1002333D01*
X-1001517Y-511833D01*
X-1001050Y-510833D01*
X-1000817Y-509667D01*
X-1001050Y-508500D01*
X-1001750Y-507500D01*
X-1002567Y-507167D01*
X-1006183D01*
G01X-985083Y-515833D02*
X-986250Y-514167D01*
X-986833Y-512500D01*
Y-505834D01*
X-986250Y-504167D01*
X-985083Y-502500D01*
G01X-975000Y-512500D02*
X-975933Y-512333D01*
X-976750Y-511667D01*
X-977450Y-510667D01*
X-977917Y-509500D01*
X-978150Y-508167D01*
Y-506833D01*
X-977917Y-505500D01*
X-977450Y-504333D01*
X-976750Y-503333D01*
X-975933Y-502667D01*
X-975000Y-502500D01*
X-974067Y-502667D01*
X-973250Y-503333D01*
X-972550Y-504333D01*
X-972083Y-505500D01*
X-971850Y-506833D01*
Y-508167D01*
X-972083Y-509500D01*
X-972550Y-510667D01*
X-973250Y-511667D01*
X-974067Y-512333D01*
X-975000Y-512500D01*
G01X-967950Y-511167D02*
X-967017Y-512000D01*
X-965967Y-512500D01*
X-965033D01*
X-964100Y-512000D01*
X-963400Y-511167D01*
X-963050Y-510000D01*
X-963283Y-508834D01*
X-963867Y-507833D01*
X-964917Y-507167D01*
X-966317Y-506833D01*
X-967133Y-506167D01*
X-967483Y-505000D01*
X-967250Y-503833D01*
X-966667Y-503000D01*
X-965850Y-502500D01*
X-965033D01*
X-964217Y-502833D01*
X-963517Y-503667D01*
G01X-958333Y-512500D02*
Y-502500D01*
X-955533D01*
X-954600Y-503000D01*
X-953900Y-504167D01*
X-953667Y-505500D01*
X-953900Y-506833D01*
X-954483Y-507833D01*
X-955533Y-508334D01*
X-958333D01*
G01X-945917Y-515833D02*
X-944750Y-514167D01*
X-944167Y-512500D01*
Y-505834D01*
X-944750Y-504167D01*
X-945917Y-502500D01*
G01X-902000Y-470000D02*
Y-460000D01*
X-903400Y-462000D01*
G01Y-470000D02*
X-900600D01*
G01X-892500Y-470333D02*
X-892733Y-470167D01*
Y-469833D01*
X-892500Y-469667D01*
X-892267Y-469833D01*
Y-470167D01*
X-892500Y-470333D01*
G01Y-465834D02*
X-892733Y-465667D01*
Y-465333D01*
X-892500Y-465167D01*
X-892267Y-465333D01*
Y-465667D01*
X-892500Y-465834D01*
G01X-883000Y-470000D02*
Y-460000D01*
X-884400Y-462000D01*
G01Y-470000D02*
X-881600D01*
G01X-785060Y-472187D02*
X-784127Y-473020D01*
X-783077Y-473520D01*
X-782143D01*
X-781210Y-473020D01*
X-780510Y-472187D01*
X-780160Y-471020D01*
X-780393Y-469854D01*
X-780977Y-468853D01*
X-782027Y-468187D01*
X-783427Y-467853D01*
X-784243Y-467187D01*
X-784593Y-466020D01*
X-784360Y-464853D01*
X-783777Y-464020D01*
X-782960Y-463520D01*
X-782143D01*
X-781327Y-463853D01*
X-780627Y-464687D01*
G01X-775560Y-473520D02*
Y-463520D01*
G01X-770660D02*
Y-473520D01*
G01Y-468520D02*
X-775560D01*
G01X-766527Y-473520D02*
X-763610Y-463520D01*
X-760693Y-473520D01*
G01X-761743Y-470020D02*
X-765477D01*
G01X-757610Y-463520D02*
X-755977Y-473520D01*
X-754110Y-463520D01*
X-752243Y-473520D01*
X-750610Y-463520D01*
G01X-668067Y-470500D02*
X-667367Y-471667D01*
X-666433Y-472333D01*
X-665383Y-472500D01*
X-664450Y-472333D01*
X-663517Y-471500D01*
X-662933Y-470500D01*
X-662817Y-469500D01*
X-663050Y-468334D01*
X-663867Y-467500D01*
X-664683Y-467167D01*
X-665733D01*
G01X-664683D02*
X-663983Y-466667D01*
X-663400Y-465834D01*
X-663167Y-464833D01*
X-663400Y-463833D01*
X-663983Y-463000D01*
X-665033Y-462500D01*
X-666083Y-462667D01*
X-667133Y-463333D01*
G01X-656000Y-462500D02*
X-656933Y-462833D01*
X-657633Y-463667D01*
X-658100Y-464667D01*
X-658450Y-466000D01*
X-658567Y-467500D01*
X-658450Y-469000D01*
X-658100Y-470333D01*
X-657633Y-471334D01*
X-656933Y-472167D01*
X-656000Y-472500D01*
X-655067Y-472167D01*
X-654367Y-471334D01*
X-653900Y-470333D01*
X-653550Y-469000D01*
X-653433Y-467500D01*
X-653550Y-466000D01*
X-653900Y-464667D01*
X-654367Y-463667D01*
X-655067Y-462833D01*
X-656000Y-462500D01*
G01X-648017Y-469167D02*
X-644983D01*
G01X-639917Y-472500D02*
X-637000Y-462500D01*
X-634083Y-472500D01*
G01X-635133Y-469000D02*
X-638867D01*
G01X-629833Y-472500D02*
Y-462500D01*
X-627033D01*
X-626100Y-463000D01*
X-625400Y-464167D01*
X-625167Y-465500D01*
X-625400Y-466833D01*
X-625983Y-467833D01*
X-627033Y-468334D01*
X-629833D01*
G01X-620333Y-472500D02*
Y-462500D01*
X-617417D01*
X-616483Y-463000D01*
X-615900Y-463667D01*
X-615667Y-465000D01*
X-615900Y-466333D01*
X-616600Y-467167D01*
X-617417Y-467667D01*
X-620333D01*
G01X-617417D02*
X-615667Y-472500D01*
G01X-610017Y-469167D02*
X-606983D01*
G01X-599000Y-472500D02*
Y-462500D01*
X-600400Y-464500D01*
G01Y-472500D02*
X-597600D01*
G01X-588100D02*
Y-462500D01*
X-592417Y-469667D01*
X-586583D01*
G54D11*
G01X-1174900Y-473500D02*
X-1171300Y-466100D01*
X-1171800Y-465700D01*
X-1175900Y-473200D01*
X-1176200Y-471200D01*
X-1172500Y-465400D01*
X-1175700Y-471300D01*
X-1176500Y-469800D01*
X-1172900Y-464900D01*
X-1173600Y-451800D01*
X-1173700Y-449900D01*
X-1182100D01*
X-1187400Y-473000D01*
X-1182400D01*
X-1177800Y-456000D01*
X-1177000Y-455900D01*
X-1176100Y-468500D01*
X-1173700Y-464500D01*
X-1174600Y-450800D01*
X-1181500Y-450900D01*
X-1186400Y-472100D01*
X-1183100D01*
X-1178300Y-454800D01*
X-1176600Y-455000D01*
X-1175500Y-466300D01*
X-1174600Y-464300D01*
X-1175400Y-451700D01*
X-1181000Y-451800D01*
X-1185300Y-471300D01*
X-1183800Y-471400D01*
X-1179000Y-454300D01*
X-1176200D01*
X-1175200Y-462200D01*
X-1176200Y-452500D01*
X-1180500Y-452800D01*
X-1184300Y-470600D01*
X-1179700Y-453400D01*
X-1176800D01*
G01X-1182820Y-448900D02*
X-1188360Y-473900D01*
X-1181580D01*
X-1177300Y-456700D01*
X-1176920Y-473900D01*
X-1172260D01*
X-1163400Y-456920D01*
X-1167240Y-473900D01*
X-1160380D01*
X-1154840Y-448900D01*
X-1164540D01*
X-1172540Y-464820D01*
X-1172880Y-448900D01*
X-1182820D01*
G01X-1155800Y-449500D02*
X-1161100Y-472900D01*
X-1166100Y-473000D01*
X-1166000Y-471900D01*
X-1161800Y-472100D01*
X-1161300Y-471000D01*
X-1165900Y-471100D01*
X-1165700Y-470000D01*
X-1161300D01*
X-1160800Y-469200D01*
X-1165300Y-469100D01*
X-1165200Y-468100D01*
X-1160700D01*
X-1160400Y-467100D01*
X-1165100Y-467200D01*
X-1164900Y-466300D01*
X-1160300Y-466200D01*
X-1160000Y-465200D01*
X-1164700Y-465300D01*
X-1164400Y-464200D01*
X-1159700Y-464300D01*
X-1159300Y-463100D01*
X-1164700Y-463500D01*
X-1164000Y-462500D01*
X-1159500Y-462600D01*
X-1159000Y-461700D01*
X-1163900D01*
X-1163600Y-460600D01*
X-1159100Y-460800D01*
X-1158800Y-459900D01*
X-1163200D01*
X-1163100Y-459200D01*
X-1158800D01*
X-1158300Y-458500D01*
X-1163000Y-458400D01*
X-1162900Y-457800D01*
X-1158400Y-457900D01*
X-1158200Y-457200D01*
X-1162500Y-457000D01*
X-1163100Y-456500D01*
X-1157800D01*
X-1157500Y-455500D01*
X-1156600Y-449800D01*
X-1164000D01*
X-1164500Y-450700D01*
X-1157600D01*
X-1157800Y-451700D01*
X-1165000Y-451600D01*
X-1165400Y-452400D01*
X-1157900Y-452500D01*
X-1157800Y-453500D01*
X-1165900Y-453200D01*
X-1166200Y-453900D01*
X-1158000Y-454300D01*
X-1158300Y-455300D01*
X-1166600Y-454800D01*
X-1158900Y-455900D01*
X-1167000Y-455600D01*
X-1163500Y-456400D01*
X-1167300Y-456300D01*
X-1171700Y-465200D01*
X-1169200Y-466400D01*
X-1164500Y-457200D01*
X-1166900Y-457100D01*
X-1170600Y-465200D01*
X-1169500Y-465500D01*
X-1166000Y-457800D01*
G01X-1170300Y-466300D02*
X-1174000Y-473600D01*
G01X-1169500Y-466900D02*
X-1172800Y-473000D01*
G01X-1152800Y-456400D02*
X-1156600Y-473100D01*
X-1152200Y-473000D01*
X-1148300Y-456600D01*
X-1149500D01*
X-1152900Y-472000D01*
X-1155600Y-472300D01*
X-1152100Y-456500D01*
X-1150400Y-456400D01*
X-1153600Y-471200D01*
X-1154500Y-471400D01*
X-1151400Y-457200D01*
G01X-1153420Y-455700D02*
X-1157540Y-473900D01*
X-1151380D01*
X-1147440Y-455700D01*
X-1153420D01*
G01X-1151600Y-450100D02*
X-1146700Y-450000D01*
X-1147000Y-451000D01*
X-1151700D01*
G01X-1152020Y-448900D02*
X-1152660Y-451900D01*
X-1146380D01*
X-1145740Y-448900D01*
X-1152020D01*
G01X-1129400Y-468900D02*
X-1131800Y-471900D01*
X-1136500Y-473700D01*
X-1142100Y-473600D01*
X-1144600Y-472300D01*
X-1145800Y-471000D01*
X-1146400Y-469500D01*
X-1146700Y-467600D01*
X-1146500Y-464600D01*
X-1145400Y-461200D01*
X-1143500Y-459100D01*
X-1140200Y-456900D01*
X-1136100Y-456200D01*
X-1132300Y-456400D01*
X-1129400Y-457900D01*
X-1127500Y-460900D01*
X-1132500Y-461000D01*
X-1133400Y-459200D01*
X-1135100Y-458100D01*
X-1136800Y-458000D01*
X-1138600Y-458900D01*
X-1140300Y-460700D01*
X-1141800Y-463600D01*
X-1142400Y-466600D01*
X-1141500Y-470400D01*
X-1140200Y-471500D01*
X-1138300Y-471600D01*
X-1136300Y-471400D01*
X-1134500Y-469100D01*
X-1130300Y-469000D01*
X-1132500Y-471200D01*
X-1134900Y-472000D01*
X-1137200Y-472800D01*
X-1142300Y-472700D01*
X-1144900Y-470600D01*
X-1145800Y-467400D01*
X-1145500Y-465100D01*
X-1144700Y-462000D01*
X-1143300Y-460200D01*
X-1139800Y-457700D01*
X-1135400Y-457000D01*
X-1131300Y-457600D01*
X-1128800Y-460100D01*
X-1132100D01*
X-1134300Y-457900D01*
X-1130100Y-458800D01*
X-1129500Y-459400D01*
X-1132600Y-459000D01*
G01X-1133300Y-461900D02*
Y-461420D01*
X-1133640Y-460240D01*
X-1134300Y-459200D01*
X-1135200Y-458900D01*
X-1136580D01*
X-1138060Y-459820D01*
X-1139360Y-461000D01*
X-1140240Y-462220D01*
X-1140880Y-463920D01*
X-1141300Y-465380D01*
X-1141500Y-467060D01*
Y-468020D01*
X-1141020Y-469220D01*
X-1139780Y-470700D01*
X-1137160D01*
X-1135840Y-469500D01*
X-1134980Y-468200D01*
X-1134940Y-468100D01*
X-1128180D01*
X-1128240Y-468240D01*
X-1128840Y-469340D01*
X-1129020Y-469800D01*
X-1129740Y-470700D01*
X-1130500Y-471460D01*
X-1131660Y-472420D01*
X-1132820Y-473200D01*
X-1133740Y-473740D01*
X-1136380Y-474500D01*
X-1141640D01*
X-1142540Y-474320D01*
X-1144220Y-473760D01*
X-1144900Y-473240D01*
X-1146240Y-471900D01*
X-1146780Y-471180D01*
X-1146940Y-470880D01*
X-1147320Y-469660D01*
X-1147500Y-468640D01*
Y-464780D01*
X-1146940Y-462540D01*
X-1146380Y-461580D01*
X-1145980Y-460780D01*
X-1145420Y-459880D01*
X-1143700Y-458140D01*
X-1142740Y-457380D01*
X-1142000Y-456820D01*
X-1140240Y-456040D01*
X-1139500Y-455660D01*
X-1138800Y-455480D01*
X-1137260Y-455300D01*
X-1134320D01*
X-1132020Y-455500D01*
X-1130940Y-455860D01*
X-1130580Y-456020D01*
X-1129260Y-456780D01*
X-1128940Y-457100D01*
X-1127820Y-458420D01*
X-1127060Y-460300D01*
X-1126900Y-460800D01*
Y-461900D01*
X-1133300D01*
G01X-1137900Y-458000D02*
X-1140300Y-459100D01*
X-1142500Y-460900D01*
X-1143900Y-462600D01*
X-1144800Y-467600D01*
X-1144200Y-470000D01*
X-1141000Y-472300D01*
X-1136400Y-472200D01*
X-1131600Y-469600D01*
X-1135400Y-470400D01*
X-1141100Y-471400D01*
X-1142100Y-470700D01*
X-1142700Y-469000D01*
X-1143100Y-467100D01*
X-1142700Y-464100D01*
X-1140500Y-459900D01*
X-1143400Y-463700D01*
X-1143600Y-465700D01*
X-1143900Y-467700D01*
X-1143000Y-469900D01*
G01X-1113500Y-459200D02*
X-1123500Y-459300D01*
X-1123700Y-460100D01*
X-1114300Y-460000D01*
X-1116500Y-460800D01*
X-1124200Y-461000D01*
X-1124400Y-461900D01*
X-1117600Y-461800D01*
X-1118800Y-462800D01*
X-1124500Y-462700D01*
X-1124600Y-463600D01*
X-1119300Y-463700D01*
X-1120100Y-464800D01*
X-1125000Y-464600D01*
Y-465500D01*
X-1120600Y-465700D01*
X-1120800Y-466700D01*
X-1125300Y-466500D01*
X-1125500Y-467400D01*
X-1121000Y-467600D01*
X-1121200Y-468700D01*
X-1125600Y-468400D01*
X-1125900Y-469100D01*
X-1121500Y-469500D01*
X-1121700Y-470700D01*
X-1126100Y-470000D01*
X-1126200Y-470700D01*
X-1121900Y-471200D01*
X-1122100Y-472000D01*
X-1126300Y-471700D01*
X-1126700Y-472300D01*
X-1122100Y-472700D01*
X-1122200Y-473100D01*
X-1126800Y-473200D01*
G01X-1114060Y-460760D02*
X-1114840Y-460920D01*
X-1115740Y-461140D01*
X-1116880Y-461820D01*
X-1117700Y-462640D01*
X-1118620Y-463340D01*
X-1118840Y-464020D01*
X-1119440Y-464820D01*
X-1119660Y-465480D01*
X-1120060Y-466280D01*
X-1120280Y-466960D01*
X-1120480Y-468360D01*
X-1120680Y-468940D01*
X-1120880Y-469940D01*
X-1121080Y-470540D01*
X-1121700Y-472980D01*
X-1121820Y-473900D01*
X-1127640D01*
X-1126920Y-471060D01*
X-1126720Y-470440D01*
X-1126500Y-468800D01*
X-1126320Y-467860D01*
X-1126120Y-467260D01*
X-1125920Y-466260D01*
X-1125720Y-465660D01*
X-1125300Y-464000D01*
X-1125120Y-462220D01*
X-1124920Y-461660D01*
X-1124720Y-460660D01*
X-1124520Y-460060D01*
X-1123720Y-456800D01*
X-1123580Y-455700D01*
X-1117880D01*
X-1118100Y-456160D01*
Y-458740D01*
X-1116500Y-457160D01*
X-1115780Y-456620D01*
X-1114680Y-456060D01*
X-1113560Y-455680D01*
X-1112460Y-455500D01*
X-1111720D01*
X-1112460Y-458440D01*
X-1114060Y-460760D01*
G01X-1123100Y-456500D02*
X-1118900Y-456600D01*
X-1118800Y-457600D01*
X-1123100Y-457500D01*
X-1123300Y-458500D01*
X-1113100Y-458400D01*
X-1112600Y-456400D01*
X-1116100Y-457600D01*
X-1113500D01*
G01X-1105100Y-471100D02*
X-1104060D01*
X-1103780Y-470820D01*
X-1103200Y-470640D01*
X-1102080Y-469740D01*
X-1100800Y-468240D01*
X-1100380Y-467400D01*
X-1100180Y-467100D01*
X-1099960Y-466660D01*
X-1099540Y-465720D01*
X-1099320Y-465060D01*
X-1099100Y-464180D01*
Y-461220D01*
X-1099360Y-460200D01*
X-1099660Y-459900D01*
X-1100700Y-458640D01*
X-1101220Y-458300D01*
X-1103340D01*
X-1103700Y-458640D01*
X-1105300Y-459840D01*
X-1105760Y-460320D01*
X-1106180Y-460940D01*
X-1107060Y-462020D01*
X-1107260Y-462880D01*
X-1107660Y-463660D01*
X-1108100Y-465000D01*
Y-468640D01*
X-1107620Y-469600D01*
X-1107140Y-470340D01*
X-1105980Y-471100D01*
X-1105100D01*
G01X-1112540Y-460460D02*
X-1110680Y-458140D01*
X-1109940Y-457580D01*
X-1109000Y-456840D01*
X-1108480Y-456660D01*
X-1107940Y-456400D01*
X-1107740Y-456200D01*
X-1107480Y-456060D01*
X-1106880Y-455860D01*
X-1106480Y-455660D01*
X-1105960Y-455480D01*
X-1104600Y-455300D01*
X-1103440Y-455100D01*
X-1100940D01*
X-1098240Y-455480D01*
X-1097720Y-455660D01*
X-1097020Y-456020D01*
X-1096180Y-456640D01*
X-1095620Y-456820D01*
X-1095540Y-456900D01*
X-1094200Y-458440D01*
X-1093660Y-459520D01*
X-1093460Y-460100D01*
X-1093100Y-461020D01*
Y-464400D01*
X-1093420Y-465360D01*
X-1094300Y-465520D01*
X-1094720Y-465740D01*
X-1095320Y-465940D01*
X-1096120Y-466340D01*
X-1096720Y-466540D01*
X-1097100Y-466720D01*
X-1098100Y-466920D01*
X-1098520Y-467140D01*
X-1099160Y-467360D01*
X-1101180Y-468700D01*
X-1094660D01*
X-1095220Y-469800D01*
X-1095560Y-470320D01*
X-1097480Y-472220D01*
X-1099940Y-473740D01*
X-1102580Y-474500D01*
X-1108800D01*
X-1109300Y-474340D01*
X-1111220Y-473560D01*
X-1111720Y-473240D01*
X-1113240Y-471720D01*
X-1113560Y-471240D01*
X-1113760Y-470660D01*
X-1114140Y-469980D01*
X-1114320Y-469120D01*
X-1114500Y-468680D01*
Y-464980D01*
X-1114320Y-464260D01*
X-1114140Y-463720D01*
X-1113940Y-463320D01*
X-1113720Y-462660D01*
X-1113560Y-462000D01*
X-1111880Y-460320D01*
X-1112540Y-460460D01*
G01X-1099300Y-466400D02*
X-1093800Y-464400D01*
X-1093900Y-461100D01*
X-1094800Y-459000D01*
X-1096800Y-457300D01*
X-1100000Y-456100D01*
X-1102800Y-455900D01*
X-1106300Y-456300D01*
X-1109600Y-458100D01*
X-1111400Y-460500D01*
X-1112900Y-462600D01*
X-1113600Y-465600D01*
X-1113500Y-469100D01*
X-1112100Y-471900D01*
X-1109600Y-473300D01*
X-1105700Y-473800D01*
X-1101000Y-473400D01*
X-1098200Y-471800D01*
X-1096600Y-470100D01*
X-1096000Y-469500D01*
X-1100800Y-469700D01*
X-1102300Y-471100D01*
X-1097900Y-470400D01*
X-1100300Y-471800D01*
X-1103200Y-471400D01*
X-1100600Y-472600D01*
X-1103000D01*
X-1103700Y-471900D01*
X-1103400Y-473000D01*
X-1104600Y-471900D01*
X-1106200D01*
X-1104100Y-473100D01*
X-1107200Y-472700D01*
X-1110100Y-472100D01*
X-1111500Y-470900D01*
X-1112600Y-468600D01*
X-1112700Y-466000D01*
X-1112400Y-463700D01*
X-1111400Y-461600D01*
X-1109600Y-459500D01*
X-1108100Y-458200D01*
X-1105900Y-457200D01*
X-1102200Y-456700D01*
X-1099600Y-457300D01*
X-1097000Y-458400D01*
X-1095500Y-459500D01*
X-1094600Y-461900D01*
X-1094500Y-463900D01*
X-1098800Y-465200D01*
X-1098600Y-464000D01*
X-1095100Y-463100D01*
X-1095300Y-462000D01*
X-1098500Y-463000D01*
X-1098600Y-461700D01*
X-1095600Y-461300D01*
X-1095900Y-460200D01*
X-1098400Y-460700D01*
X-1098900Y-459900D01*
X-1096600Y-459400D01*
X-1097100Y-458900D01*
X-1099400Y-459000D01*
X-1098800Y-458500D01*
X-1100600Y-458000D01*
X-1102400Y-457400D01*
X-1104200Y-457500D01*
X-1106200Y-458100D01*
X-1107900Y-459000D01*
X-1110500Y-462200D01*
X-1111800Y-464800D01*
Y-467700D01*
X-1110700Y-470300D01*
X-1108700Y-472000D01*
X-1106600Y-471900D01*
X-1107900Y-470300D01*
X-1108900Y-468700D01*
Y-465500D01*
X-1107900Y-462300D01*
X-1106500Y-459900D01*
X-1104100Y-458200D01*
X-1108000Y-460000D01*
X-1108100Y-461500D01*
X-1108700Y-461200D01*
X-1110300Y-463600D01*
X-1111000Y-466000D01*
X-1110700Y-468100D01*
X-1109500Y-470600D01*
X-1107700Y-471400D01*
X-1109300Y-469100D01*
X-1109800Y-467600D01*
X-1108600Y-462200D01*
X-1110400Y-466800D01*
G01X-1113600Y-460900D02*
X-1112100Y-459000D01*
G01X-1093100Y-469400D02*
X-1087900Y-469700D01*
X-1086500Y-471400D01*
X-1083400Y-472300D01*
X-1081000Y-472000D01*
X-1079300Y-470600D01*
X-1079000Y-468900D01*
X-1079500Y-467700D01*
X-1080300Y-466600D01*
X-1081800Y-466000D01*
X-1083300Y-465500D01*
X-1085300Y-465000D01*
X-1087900Y-464000D01*
X-1089100Y-463200D01*
X-1089800Y-461000D01*
X-1089500Y-459000D01*
X-1088600Y-457700D01*
X-1086500Y-456700D01*
X-1084600Y-456100D01*
X-1081900Y-455900D01*
X-1079900Y-455800D01*
X-1076900Y-456300D01*
X-1075000Y-457000D01*
X-1073700Y-458000D01*
X-1073300Y-459400D01*
X-1077600Y-459500D01*
X-1078100Y-458800D01*
X-1074300Y-458500D01*
X-1074600Y-457800D01*
X-1078200Y-458200D01*
X-1076000Y-457400D01*
X-1079100Y-457700D01*
X-1077100Y-456900D01*
X-1080100Y-457300D01*
X-1079200Y-456600D01*
X-1083100Y-456800D01*
X-1080600Y-457300D01*
X-1083400Y-457700D01*
X-1083600Y-457000D01*
X-1087900Y-458400D01*
X-1084000Y-458100D01*
X-1088600Y-459100D01*
X-1088800Y-461500D01*
X-1087700Y-463600D01*
X-1084400Y-464300D01*
X-1081200Y-465400D01*
X-1078800Y-467300D01*
X-1078300Y-470500D01*
X-1079900Y-472600D01*
X-1083500Y-473300D01*
X-1085600Y-472600D01*
X-1088800Y-470500D01*
X-1092600Y-470200D01*
X-1092100Y-471800D01*
X-1091700Y-471300D01*
X-1089300Y-471500D01*
X-1091300Y-472300D01*
X-1088700Y-471600D01*
X-1084000Y-473500D01*
X-1089100D01*
X-1091000Y-472900D01*
X-1087200Y-472800D01*
X-1082700Y-473700D01*
X-1079000Y-473600D01*
X-1076500Y-472300D01*
X-1074700Y-470600D01*
X-1074300Y-467300D01*
X-1074800Y-465300D01*
X-1078800Y-463600D01*
X-1081600Y-462900D01*
X-1083400Y-462500D01*
X-1084800Y-461500D01*
X-1085000Y-458900D01*
X-1088100Y-459800D01*
X-1087200Y-462700D01*
X-1085000Y-463400D01*
X-1082000Y-464100D01*
X-1079600Y-465100D01*
X-1078200Y-466500D01*
X-1077700Y-468500D01*
X-1077500Y-470100D01*
X-1079200Y-472800D01*
X-1076800Y-471400D01*
X-1075300Y-470000D01*
X-1077300Y-470900D01*
X-1075000Y-468800D01*
X-1075200Y-466100D01*
X-1082700Y-462700D01*
X-1084200Y-462900D01*
X-1086600Y-461800D01*
X-1087200Y-460300D01*
X-1085800Y-459800D01*
X-1086600Y-461000D01*
X-1085300Y-460400D01*
X-1085600Y-461400D01*
X-1076700Y-466500D01*
X-1075900Y-467100D01*
X-1075700Y-468400D01*
X-1076800Y-469500D01*
X-1077800Y-466200D01*
X-1075900Y-468800D01*
G01X-1093780Y-468700D02*
X-1087100D01*
Y-469740D01*
X-1086800Y-470060D01*
X-1086520Y-470600D01*
X-1085820Y-470820D01*
X-1085660Y-471000D01*
X-1085120Y-471260D01*
X-1084400Y-471500D01*
X-1082360D01*
X-1080540Y-470600D01*
X-1080100Y-470140D01*
Y-469780D01*
X-1079840Y-469380D01*
X-1080380Y-467740D01*
X-1081440Y-466940D01*
X-1082560Y-466720D01*
X-1085740Y-465920D01*
X-1086940Y-465520D01*
X-1087600Y-465360D01*
X-1087740Y-465200D01*
X-1088540Y-464800D01*
X-1089140Y-464200D01*
X-1089540Y-464000D01*
X-1089800Y-463740D01*
X-1090000Y-463340D01*
X-1090180Y-463180D01*
X-1090500Y-462200D01*
Y-459800D01*
X-1090320Y-459260D01*
X-1090140Y-458500D01*
X-1090000Y-458260D01*
X-1089000Y-457260D01*
X-1088860Y-456940D01*
X-1085920Y-455480D01*
X-1083620Y-455100D01*
X-1082060Y-454900D01*
X-1080520D01*
X-1078580Y-455100D01*
X-1076240Y-455480D01*
X-1075120Y-455860D01*
X-1074800Y-456020D01*
X-1073680Y-456760D01*
X-1073160Y-457300D01*
X-1072620Y-458020D01*
X-1072500Y-458240D01*
Y-460300D01*
X-1078500D01*
Y-459200D01*
X-1079580Y-458380D01*
X-1080160Y-458100D01*
X-1082380D01*
X-1083280Y-458360D01*
X-1084020Y-458940D01*
X-1084340Y-459900D01*
X-1084060Y-460720D01*
X-1083740Y-461340D01*
X-1081860Y-462280D01*
X-1079400Y-462500D01*
X-1078660Y-462680D01*
X-1078100Y-462860D01*
X-1076500Y-463460D01*
X-1075320Y-463860D01*
X-1075060Y-464000D01*
X-1073820Y-465220D01*
X-1073480Y-466260D01*
X-1073300Y-467160D01*
Y-468420D01*
X-1073860Y-470700D01*
X-1074000Y-470960D01*
X-1075140Y-472300D01*
X-1075280Y-472440D01*
X-1076600Y-473380D01*
X-1077320Y-473740D01*
X-1079600Y-474500D01*
X-1088240D01*
X-1089160Y-474320D01*
X-1089920Y-474120D01*
X-1090860Y-473760D01*
X-1091560Y-473400D01*
X-1092700Y-472460D01*
X-1093180Y-471980D01*
X-1093340Y-471480D01*
X-1093520Y-471100D01*
X-1093700Y-470320D01*
X-1093780Y-468700D01*
G01X-1095100D02*
X-1092800D01*
G01X-1058300Y-469400D02*
X-1055400Y-467100D01*
X-1053900Y-463700D01*
X-1054400Y-461200D01*
X-1055900Y-459900D01*
X-1054800Y-463500D01*
X-1055400Y-463600D01*
X-1054600Y-464500D01*
X-1055700D01*
X-1055400Y-465300D01*
X-1056200Y-466800D01*
G01X-1059300Y-457700D02*
X-1059100Y-455600D01*
X-1055200Y-456300D01*
X-1052700Y-457900D01*
X-1051100Y-460800D01*
X-1050900Y-465200D01*
X-1052900Y-469400D01*
X-1055300Y-471900D01*
X-1059000Y-473500D01*
X-1066000D01*
X-1068000Y-471900D01*
X-1070200Y-468700D01*
X-1070600Y-464500D01*
X-1069000Y-460500D01*
X-1066000Y-457500D01*
X-1063000Y-456500D01*
X-1059200Y-456000D01*
X-1053000Y-458500D01*
X-1052000Y-461500D01*
Y-465700D01*
X-1053400Y-468600D01*
X-1055700Y-471000D01*
X-1058900Y-472600D01*
X-1063700Y-473000D01*
X-1065900Y-473600D01*
X-1068300Y-472900D01*
X-1070600Y-469300D01*
X-1065100Y-472600D01*
X-1060800Y-472200D01*
X-1057200Y-470700D01*
X-1055200Y-469100D01*
X-1053300Y-466500D01*
X-1052500Y-463400D01*
X-1052900Y-460100D01*
X-1057000Y-457400D01*
X-1058700Y-457200D01*
X-1057000Y-458500D01*
X-1055100Y-459800D01*
X-1053800Y-460900D01*
X-1053400Y-463100D01*
X-1053600Y-465600D01*
X-1054800Y-467500D01*
X-1056400Y-469200D01*
X-1058500Y-470200D01*
X-1060200Y-470700D01*
X-1061500Y-471400D01*
X-1063300Y-471600D01*
X-1065400Y-471500D01*
X-1069000Y-469300D01*
X-1069600Y-466400D01*
X-1069700Y-463700D01*
X-1068600Y-461200D01*
X-1066700Y-459200D01*
X-1063900Y-457600D01*
X-1061100Y-457000D01*
X-1059600D01*
X-1060200Y-457500D01*
X-1063300Y-458000D01*
X-1065300Y-459500D01*
X-1066900Y-460600D01*
X-1067900Y-462100D01*
X-1068800Y-464300D01*
X-1068700Y-466900D01*
X-1068200Y-469100D01*
X-1066900Y-470200D01*
X-1064300Y-470900D01*
X-1065700Y-469300D01*
X-1065800Y-465900D01*
X-1065300Y-462900D01*
X-1061200Y-458200D01*
X-1063600Y-458900D01*
X-1066400Y-461300D01*
X-1067800Y-464200D01*
Y-467200D01*
X-1067400Y-469300D01*
X-1066300Y-469700D01*
X-1067100Y-466400D01*
X-1066600Y-463400D01*
X-1064700Y-460000D01*
X-1062600Y-458800D01*
X-1065300Y-461700D01*
X-1066700Y-467400D01*
G01X-1060840Y-455100D02*
X-1057160D01*
X-1055260Y-455480D01*
X-1054740Y-455640D01*
X-1053380Y-456420D01*
X-1052660Y-456800D01*
X-1052020Y-457420D01*
X-1051820Y-458020D01*
X-1051200Y-458660D01*
X-1051000Y-459060D01*
X-1050840Y-459200D01*
X-1050700Y-459780D01*
Y-460140D01*
X-1050400Y-460460D01*
X-1050280Y-460680D01*
X-1050100Y-461740D01*
Y-464240D01*
X-1050280Y-465160D01*
X-1050480Y-465980D01*
X-1050680Y-467120D01*
X-1051220Y-468180D01*
X-1051840Y-469020D01*
X-1052040Y-469600D01*
X-1052740Y-470500D01*
X-1054480Y-472240D01*
X-1055000Y-472580D01*
X-1055420Y-472780D01*
X-1056220Y-473380D01*
X-1056920Y-473740D01*
X-1059380Y-474500D01*
X-1065600D01*
X-1067860Y-473740D01*
X-1068160Y-473600D01*
X-1069500Y-472460D01*
X-1069820Y-472120D01*
X-1070380Y-471200D01*
X-1071140Y-469860D01*
X-1071300Y-469400D01*
Y-464580D01*
X-1071120Y-463880D01*
X-1070740Y-462900D01*
X-1070540Y-462320D01*
X-1069980Y-461000D01*
X-1068840Y-459500D01*
X-1066900Y-457560D01*
X-1066180Y-457020D01*
X-1065400Y-456620D01*
X-1064440Y-456040D01*
X-1063500Y-455660D01*
X-1062940Y-455480D01*
X-1060840Y-455100D01*
G01X-1057800Y-458580D02*
X-1057000Y-459120D01*
X-1056760Y-459840D01*
X-1056340Y-460460D01*
X-1056100Y-461640D01*
Y-463760D01*
X-1056320Y-464860D01*
X-1056720Y-466060D01*
X-1056940Y-466920D01*
X-1057200Y-467460D01*
X-1057640Y-467880D01*
X-1058040Y-468480D01*
X-1059960Y-470420D01*
X-1061020Y-470840D01*
X-1061420Y-471100D01*
X-1062720D01*
X-1063340Y-470840D01*
X-1063860Y-470600D01*
X-1064360Y-470080D01*
X-1064820Y-469400D01*
X-1065100Y-468840D01*
Y-464920D01*
X-1064880Y-464120D01*
X-1064420Y-462780D01*
X-1064160Y-462520D01*
X-1063620Y-461700D01*
X-1063200Y-460840D01*
X-1062500Y-460140D01*
X-1062120Y-459860D01*
X-1061720Y-459360D01*
X-1060600Y-458580D01*
X-1060040Y-458300D01*
X-1058360D01*
X-1057800Y-458580D01*
G01X-1040300Y-459100D02*
X-1041400Y-464800D01*
G01X-1044800Y-458200D02*
X-1041400D01*
X-1044300Y-472700D01*
X-1047400Y-472300D01*
X-1044100Y-458800D01*
X-1042400Y-459100D01*
X-1045100Y-471900D01*
X-1046500D01*
X-1043400Y-459700D01*
X-1045600Y-471500D01*
G01X-1036600Y-449900D02*
X-1036800Y-451300D01*
X-1038600Y-452400D01*
X-1039800Y-456100D01*
X-1033700Y-456500D01*
X-1032300Y-452100D01*
X-1028400Y-452000D01*
X-1028900Y-455400D01*
X-1027200Y-456600D01*
X-1025900Y-456800D01*
X-1026200Y-458200D01*
X-1030000Y-458400D01*
X-1031800Y-468900D01*
X-1030400Y-471700D01*
X-1029400D01*
X-1029600Y-473300D01*
X-1033100Y-473400D01*
X-1036100Y-472800D01*
X-1036200Y-470500D01*
X-1035900Y-467100D01*
X-1034400Y-461400D01*
X-1033800Y-458800D01*
X-1033500Y-458400D01*
X-1035000Y-458200D01*
X-1039600D01*
X-1040800Y-458300D01*
X-1043600Y-473200D01*
X-1048000Y-473000D01*
X-1045100Y-459400D01*
X-1044900Y-458400D01*
X-1048700D01*
X-1048100Y-456600D01*
X-1044900Y-456400D01*
X-1045200Y-457700D01*
X-1047600Y-457500D01*
X-1026500D01*
G01X-1049580Y-459100D02*
X-1048740Y-455700D01*
X-1044900D01*
Y-454780D01*
X-1044720Y-454060D01*
X-1044340Y-452920D01*
X-1043940Y-452120D01*
X-1043740Y-451520D01*
X-1043600Y-451260D01*
X-1042340Y-450000D01*
X-1042080Y-449860D01*
X-1040580Y-449480D01*
X-1039440Y-449300D01*
X-1036140D01*
X-1035440Y-449400D01*
X-1035480Y-449540D01*
X-1035680Y-450360D01*
X-1035880Y-451280D01*
X-1036000Y-451900D01*
X-1036740D01*
X-1037060Y-452200D01*
X-1037860Y-452600D01*
X-1038220Y-452980D01*
X-1038480Y-453740D01*
X-1038960Y-455700D01*
X-1034020D01*
X-1033720Y-455080D01*
X-1033500Y-453400D01*
X-1032940Y-451100D01*
X-1027260D01*
X-1027280Y-451180D01*
X-1027480Y-452780D01*
X-1027860Y-454280D01*
X-1028100Y-454760D01*
Y-455700D01*
X-1024800D01*
X-1024880Y-455940D01*
X-1025080Y-456940D01*
X-1025280Y-457540D01*
X-1025480Y-458560D01*
X-1025620Y-459100D01*
X-1029100D01*
Y-460000D01*
X-1029280Y-460540D01*
X-1029480Y-461540D01*
X-1029680Y-462140D01*
X-1029880Y-462960D01*
X-1030100Y-464000D01*
X-1030280Y-465560D01*
X-1030480Y-466140D01*
X-1030680Y-467140D01*
X-1030880Y-467740D01*
X-1031040Y-468400D01*
X-1031300Y-468660D01*
Y-469800D01*
X-1030300Y-470560D01*
X-1029940Y-470900D01*
X-1028220D01*
X-1028680Y-472780D01*
X-1028880Y-474120D01*
Y-474140D01*
X-1030720Y-474300D01*
X-1032860D01*
X-1034380Y-474120D01*
X-1035860Y-473740D01*
X-1036640Y-473280D01*
X-1036960Y-472660D01*
X-1037100Y-472280D01*
Y-470160D01*
X-1036920Y-469260D01*
X-1036700Y-468640D01*
X-1036500Y-466840D01*
X-1036320Y-466260D01*
X-1036120Y-465260D01*
X-1035920Y-464660D01*
X-1035720Y-463660D01*
X-1035520Y-463060D01*
X-1035320Y-462060D01*
X-1035120Y-461440D01*
X-1034820Y-459100D01*
X-1039900D01*
Y-460220D01*
X-1040280Y-461780D01*
X-1040480Y-463380D01*
X-1041280Y-466540D01*
X-1041480Y-467140D01*
X-1041700Y-468200D01*
X-1041880Y-469760D01*
X-1042080Y-470340D01*
X-1042280Y-471360D01*
X-1042480Y-472140D01*
X-1042680Y-472740D01*
X-1042880Y-473740D01*
X-1042940Y-473900D01*
X-1049140D01*
X-1048300Y-470620D01*
X-1048100Y-469020D01*
X-1047920Y-468260D01*
X-1047720Y-467660D01*
X-1047520Y-466660D01*
X-1047320Y-466060D01*
X-1047120Y-465060D01*
X-1046920Y-464460D01*
X-1046700Y-463400D01*
X-1046500Y-462020D01*
X-1046140Y-460500D01*
X-1045900Y-460040D01*
Y-459100D01*
X-1049580D01*
G01X-1038400Y-451100D02*
X-1040600Y-455800D01*
X-1043300D01*
X-1041400Y-451300D01*
X-1038900Y-451000D01*
X-1041200Y-455000D01*
X-1042000Y-455100D01*
X-1040500Y-452000D01*
G01X-1037500Y-449800D02*
X-1037800Y-451000D01*
X-1038500Y-450100D01*
X-1042000Y-450700D01*
X-1043100Y-452300D01*
X-1044100Y-455100D01*
X-1044200Y-456600D01*
X-1036600Y-456800D01*
G01X-1031100Y-472500D02*
X-1031400Y-470900D01*
X-1031900Y-472200D01*
X-1035200D01*
Y-467600D01*
X-1032000Y-453700D01*
X-1030500Y-453800D01*
X-1030000Y-456700D01*
X-1033400Y-471900D01*
X-1034300Y-471600D01*
X-1034200Y-467100D01*
X-1031400Y-454500D01*
X-1030700Y-456500D01*
X-1033700Y-470600D01*
X-1032700Y-461100D01*
G01X-1032000Y-452900D02*
X-1029300D01*
X-1028000Y-457000D01*
X-1029500Y-453600D01*
X-1029100Y-457300D01*
X-1032800Y-472800D01*
X-1030200Y-472600D01*
G54D12*
G01X-1181990Y-545833D02*
X-1181410Y-545208D01*
X-1180975Y-544167D01*
X-1180685Y-542708D01*
X-1180975Y-541458D01*
X-1181555Y-540625D01*
X-1182570Y-540000D01*
X-1186485D01*
Y-552500D01*
X-1181700D01*
X-1180685Y-551667D01*
X-1180105Y-550417D01*
X-1179815Y-548958D01*
X-1180105Y-547500D01*
X-1180975Y-546250D01*
X-1181990Y-545833D01*
X-1186485D01*
G01X-1171350Y-552500D02*
X-1172510Y-552292D01*
X-1173525Y-551459D01*
X-1174395Y-550208D01*
X-1174975Y-548750D01*
X-1175265Y-547083D01*
Y-545417D01*
X-1174975Y-543750D01*
X-1174395Y-542292D01*
X-1173525Y-541042D01*
X-1172510Y-540208D01*
X-1171350Y-540000D01*
X-1170190Y-540208D01*
X-1169175Y-541042D01*
X-1168305Y-542292D01*
X-1167725Y-543750D01*
X-1167435Y-545417D01*
Y-547083D01*
X-1167725Y-548750D01*
X-1168305Y-550208D01*
X-1169175Y-551459D01*
X-1170190Y-552292D01*
X-1171350Y-552500D01*
G01X-1163175D02*
X-1159550Y-540000D01*
X-1155925Y-552500D01*
G01X-1157230Y-548125D02*
X-1161870D01*
G01X-1150650Y-552500D02*
Y-540000D01*
X-1147025D01*
X-1145865Y-540625D01*
X-1145140Y-541458D01*
X-1144850Y-543125D01*
X-1145140Y-544792D01*
X-1146010Y-545833D01*
X-1147025Y-546458D01*
X-1150650D01*
G01X-1147025D02*
X-1144850Y-552500D01*
G01X-1139140D02*
Y-540000D01*
X-1136240D01*
X-1135080Y-540625D01*
X-1134210Y-541458D01*
X-1133485Y-542708D01*
X-1132905Y-544167D01*
X-1132760Y-546250D01*
X-1132905Y-548333D01*
X-1133485Y-549792D01*
X-1134210Y-551042D01*
X-1135080Y-551875D01*
X-1136240Y-552500D01*
X-1139140D01*
G01X-1112350D02*
X-1113510Y-552292D01*
X-1114525Y-551459D01*
X-1115395Y-550208D01*
X-1115975Y-548750D01*
X-1116265Y-547083D01*
Y-545417D01*
X-1115975Y-543750D01*
X-1115395Y-542292D01*
X-1114525Y-541042D01*
X-1113510Y-540208D01*
X-1112350Y-540000D01*
X-1111190Y-540208D01*
X-1110175Y-541042D01*
X-1109305Y-542292D01*
X-1108725Y-543750D01*
X-1108435Y-545417D01*
Y-547083D01*
X-1108725Y-548750D01*
X-1109305Y-550208D01*
X-1110175Y-551459D01*
X-1111190Y-552292D01*
X-1112350Y-552500D01*
G01X-1103740Y-540000D02*
Y-548958D01*
X-1103160Y-550834D01*
X-1102000Y-552083D01*
X-1100550Y-552500D01*
X-1099100Y-552083D01*
X-1097940Y-550834D01*
X-1097360Y-548958D01*
Y-540000D01*
G01X-1088750D02*
Y-552500D01*
G01X-1092085Y-540000D02*
X-1085415D01*
G01X-1079850D02*
Y-552500D01*
X-1074050D01*
G01X-1066890Y-540000D02*
X-1063410D01*
G01X-1065150D02*
Y-552500D01*
G01X-1066890D02*
X-1063410D01*
G01X-1056685D02*
Y-540000D01*
X-1050015Y-552500D01*
Y-540000D01*
G01X-1038650Y-552500D02*
X-1044450D01*
Y-540000D01*
X-1038650D01*
G01X-1040970Y-546042D02*
X-1044450D01*
G54D13*
G01X-1185925Y-592500D02*
X-1178575Y-577500D01*
G01X-1185925D02*
X-1178575Y-592500D01*
G01X-1168050D02*
X-1166825Y-592250D01*
X-1165425Y-591500D01*
X-1164550Y-590250D01*
X-1164200Y-588500D01*
X-1164550Y-586750D01*
X-1165600Y-585250D01*
X-1167175Y-584500D01*
X-1168925D01*
X-1169975Y-584000D01*
X-1170850Y-582750D01*
X-1171200Y-581000D01*
X-1170675Y-579250D01*
X-1169450Y-578000D01*
X-1168050Y-577500D01*
X-1166650Y-578000D01*
X-1165425Y-579250D01*
X-1164900Y-581000D01*
X-1165250Y-582750D01*
X-1166125Y-584000D01*
X-1167175Y-584500D01*
X-1168925D01*
X-1170500Y-585250D01*
X-1171550Y-586750D01*
X-1171900Y-588500D01*
X-1171550Y-590250D01*
X-1170675Y-591500D01*
X-1169275Y-592250D01*
X-1168050Y-592500D01*
G01X-1153850D02*
X-1152625Y-592250D01*
X-1151225Y-591500D01*
X-1150350Y-590250D01*
X-1150000Y-588500D01*
X-1150350Y-586750D01*
X-1151400Y-585250D01*
X-1152975Y-584500D01*
X-1154725D01*
X-1155775Y-584000D01*
X-1156650Y-582750D01*
X-1157000Y-581000D01*
X-1156475Y-579250D01*
X-1155250Y-578000D01*
X-1153850Y-577500D01*
X-1152450Y-578000D01*
X-1151225Y-579250D01*
X-1150700Y-581000D01*
X-1151050Y-582750D01*
X-1151925Y-584000D01*
X-1152975Y-584500D01*
X-1154725D01*
X-1156300Y-585250D01*
X-1157350Y-586750D01*
X-1157700Y-588500D01*
X-1157350Y-590250D01*
X-1156475Y-591500D01*
X-1155075Y-592250D01*
X-1153850Y-592500D01*
G01X-1140000D02*
X-1139650Y-589250D01*
X-1139125Y-586500D01*
X-1138425Y-584000D01*
X-1137550Y-581250D01*
X-1136150Y-577500D01*
X-1143150D01*
G01X-1129300Y-590250D02*
X-1128250Y-591500D01*
X-1127025Y-592250D01*
X-1125450Y-592500D01*
X-1123875Y-592000D01*
X-1122650Y-591000D01*
X-1121775Y-589250D01*
X-1121600Y-587250D01*
X-1121950Y-585250D01*
X-1122825Y-584000D01*
X-1124050Y-583000D01*
X-1125275Y-582750D01*
X-1126500Y-583000D01*
X-1128075Y-584000D01*
X-1127550Y-577500D01*
X-1122825D01*
G01X-1111600Y-592500D02*
X-1111250Y-589250D01*
X-1110725Y-586500D01*
X-1110025Y-584000D01*
X-1109150Y-581250D01*
X-1107750Y-577500D01*
X-1114750D01*
G01X-1097050Y-592500D02*
Y-577500D01*
X-1099150Y-580500D01*
G01Y-592500D02*
X-1094950D01*
G01X-1085125Y-587500D02*
X-1080575D01*
G01X-1068650Y-577500D02*
X-1070050Y-578000D01*
X-1071100Y-579250D01*
X-1071800Y-580750D01*
X-1072325Y-582750D01*
X-1072500Y-585000D01*
X-1072325Y-587250D01*
X-1071800Y-589250D01*
X-1071100Y-590750D01*
X-1070050Y-592000D01*
X-1068650Y-592500D01*
X-1067250Y-592000D01*
X-1066200Y-590750D01*
X-1065500Y-589250D01*
X-1064975Y-587250D01*
X-1064800Y-585000D01*
X-1064975Y-582750D01*
X-1065500Y-580750D01*
X-1066200Y-579250D01*
X-1067250Y-578000D01*
X-1068650Y-577500D01*
G01X-1054450D02*
X-1055850Y-578000D01*
X-1056900Y-579250D01*
X-1057600Y-580750D01*
X-1058125Y-582750D01*
X-1058300Y-585000D01*
X-1058125Y-587250D01*
X-1057600Y-589250D01*
X-1056900Y-590750D01*
X-1055850Y-592000D01*
X-1054450Y-592500D01*
X-1053050Y-592000D01*
X-1052000Y-590750D01*
X-1051300Y-589250D01*
X-1050775Y-587250D01*
X-1050600Y-585000D01*
X-1050775Y-582750D01*
X-1051300Y-580750D01*
X-1052000Y-579250D01*
X-1053050Y-578000D01*
X-1054450Y-577500D01*
G01X-1044100Y-590250D02*
X-1043050Y-591500D01*
X-1041825Y-592250D01*
X-1040250Y-592500D01*
X-1038675Y-592000D01*
X-1037450Y-591000D01*
X-1036575Y-589250D01*
X-1036400Y-587250D01*
X-1036750Y-585250D01*
X-1037625Y-584000D01*
X-1038850Y-583000D01*
X-1040075Y-582750D01*
X-1041300Y-583000D01*
X-1042875Y-584000D01*
X-1042350Y-577500D01*
X-1037625D01*
G01X-911875Y-592500D02*
X-907500Y-577500D01*
X-903125Y-592500D01*
G01X-904700Y-587250D02*
X-910300D01*
G54D14*
G01X-1200000Y-560000D02*
X-890000D01*
G01Y-520000D02*
X-1200000D01*
G01X-575000Y-480000D02*
X-1200000D01*
G01X-927500Y-560000D02*
Y-600000D01*
G01X-915000Y-440000D02*
Y-480000D01*
G01X-890000D02*
Y-600000D01*
G01X-870000Y-440000D02*
Y-480000D01*
G01X-680000D02*
Y-440000D01*
G01X19843Y-137795D02*
X19213D01*
G02X17244Y-135827I0J1969D01*
G01Y7244D01*
G03X5433Y19055I-11811J0D01*
G01X-1432598D01*
G03X-1442441Y9213I0J-9843D01*
G01Y-14409D01*
G02X-1448346Y-20315I-5906J0D01*
G01X-1452283D01*
G02X-1458189Y-14409I0J5906D01*
G01Y17087D01*
X-1462126Y21024D01*
X-1615394D01*
X-1619331Y17087D01*
Y-18937D01*
G02X-1622087I-1378J0D01*
G01Y17087D01*
X-1626024Y21024D01*
X-1659291D01*
X-1663228Y17087D01*
Y-180945D01*
G03X-1657323Y-186850I5906J0D01*
G01X-1280807D01*
G02X-1278839Y-188819I0J-1969D01*
G01Y-194882D01*
G03X-1276870Y-196850I1969J0D01*
G01X-1209350D01*
G03X-1207382Y-194882I0J1969D01*
G01Y-188819D01*
G02X-1205413Y-186850I1969J0D01*
G01X-410728D01*
G02X-408760Y-188819I0J-1969D01*
G01Y-194882D01*
G03X-406791Y-196850I1969J0D01*
G01X-339272D01*
G03X-337303Y-194882I0J1969D01*
G01Y-188819D01*
G02X-335335Y-186850I1969J0D01*
G01X10000D01*
G03X21811Y-175039I0J11811D01*
G01Y-139764D01*
G03X19843Y-137795I-1969J0D01*
G01X-1636850Y-74803D02*
G02X-1650236I-6693J0D01*
G01Y-60913D01*
G02X-1636850I6693J9732D01*
G01Y-74803D01*
G01X-1416378Y-145669D02*
G02X-1429764I-6693J0D01*
G01Y-131779D01*
G02X-1416378I6693J9732D01*
G01Y-145669D01*
G01X-1200000Y-600000D02*
X-575000D01*
Y-440000D01*
X-1200000D01*
Y-600000D01*
G01X-1172283Y-92362D02*
G02X-1185669I-6693J0D01*
G01Y-78472D01*
G02X-1172283I6693J9732D01*
G01Y-92362D01*
G01X-554173Y-115984D02*
G02X-567559I-6693J0D01*
G01Y-102094D01*
G02X-554173I6693J9732D01*
G01Y-115984D01*
G01X-298268Y-92362D02*
G02X-311654I-6693J0D01*
G01Y-78472D01*
G02X-298268I6693J9732D01*
G01Y-92362D01*
G01X-26024Y-129370D02*
G02X-39409I-6693J0D01*
G01Y-115480D01*
G02X-26024I6693J9732D01*
G01Y-129370D01*
G54D15*
G01X-1007500Y-470000D02*
X-1006450Y-475000D01*
X-1005250Y-470000D01*
X-1004050Y-475000D01*
X-1003000Y-470000D01*
G01X-1001125Y-475000D02*
X-999250Y-470000D01*
X-997375Y-475000D01*
G01X-998050Y-473250D02*
X-1000450D01*
G01X-994825Y-474333D02*
X-994225Y-474750D01*
X-993550Y-475000D01*
X-992950D01*
X-992350Y-474750D01*
X-991900Y-474333D01*
X-991675Y-473750D01*
X-991825Y-473167D01*
X-992200Y-472667D01*
X-992875Y-472333D01*
X-993775Y-472167D01*
X-994300Y-471833D01*
X-994525Y-471250D01*
X-994375Y-470667D01*
X-994000Y-470250D01*
X-993475Y-470000D01*
X-992950D01*
X-992425Y-470167D01*
X-991975Y-470583D01*
G01X-988825Y-475000D02*
Y-470000D01*
G01X-985675D02*
Y-475000D01*
G01Y-472500D02*
X-988825D01*
G01X-976525Y-474417D02*
X-976000Y-474833D01*
X-975400Y-475000D01*
X-974800Y-474833D01*
X-974275Y-474333D01*
X-973900Y-473583D01*
X-973750Y-472833D01*
Y-471917D01*
X-973900Y-471167D01*
X-974275Y-470500D01*
X-974725Y-470167D01*
X-975250Y-470000D01*
X-975850Y-470167D01*
X-976300Y-470500D01*
X-976600Y-471000D01*
X-976750Y-471667D01*
X-976600Y-472250D01*
X-976225Y-472833D01*
X-975775Y-473167D01*
X-975250Y-473250D01*
X-974650Y-473083D01*
X-974200Y-472667D01*
X-973750Y-471917D01*
G01X-969250Y-475000D02*
X-968725Y-474917D01*
X-968125Y-474667D01*
X-967750Y-474250D01*
X-967600Y-473667D01*
X-967750Y-473083D01*
X-968200Y-472583D01*
X-968875Y-472333D01*
X-969625D01*
X-970075Y-472167D01*
X-970450Y-471750D01*
X-970600Y-471167D01*
X-970375Y-470583D01*
X-969850Y-470167D01*
X-969250Y-470000D01*
X-968650Y-470167D01*
X-968125Y-470583D01*
X-967900Y-471167D01*
X-968050Y-471750D01*
X-968425Y-472167D01*
X-968875Y-472333D01*
X-969625D01*
X-970300Y-472583D01*
X-970750Y-473083D01*
X-970900Y-473667D01*
X-970750Y-474250D01*
X-970375Y-474667D01*
X-969775Y-474917D01*
X-969250Y-475000D01*
G01X-963250Y-470000D02*
X-963850Y-470167D01*
X-964300Y-470583D01*
X-964600Y-471083D01*
X-964825Y-471750D01*
X-964900Y-472500D01*
X-964825Y-473250D01*
X-964600Y-473917D01*
X-964300Y-474417D01*
X-963850Y-474833D01*
X-963250Y-475000D01*
X-962650Y-474833D01*
X-962200Y-474417D01*
X-961900Y-473917D01*
X-961675Y-473250D01*
X-961600Y-472500D01*
X-961675Y-471750D01*
X-961900Y-471083D01*
X-962200Y-470583D01*
X-962650Y-470167D01*
X-963250Y-470000D01*
G01X-958900Y-474250D02*
X-958450Y-474667D01*
X-957925Y-474917D01*
X-957250Y-475000D01*
X-956575Y-474833D01*
X-956050Y-474500D01*
X-955675Y-473917D01*
X-955600Y-473250D01*
X-955750Y-472583D01*
X-956125Y-472167D01*
X-956650Y-471833D01*
X-957175Y-471750D01*
X-957700Y-471833D01*
X-958375Y-472167D01*
X-958150Y-470000D01*
X-956125D01*
G01X-952675Y-470833D02*
X-952225Y-470333D01*
X-951700Y-470083D01*
X-951100Y-470000D01*
X-950350Y-470167D01*
X-949825Y-470583D01*
X-949675Y-471083D01*
X-949750Y-471583D01*
X-950050Y-472000D01*
X-951550Y-472833D01*
X-952225Y-473417D01*
X-952675Y-474250D01*
X-952825Y-475000D01*
X-949675D01*
G01X-946225Y-473333D02*
X-944275D01*
G01X-940675Y-472917D02*
X-940150Y-472333D01*
X-939700Y-472000D01*
X-939100Y-471833D01*
X-938575Y-472000D01*
X-938200Y-472333D01*
X-937900Y-472833D01*
X-937825Y-473417D01*
X-937900Y-473917D01*
X-938200Y-474417D01*
X-938650Y-474833D01*
X-939175Y-475000D01*
X-939775Y-474833D01*
X-940300Y-474333D01*
X-940600Y-473583D01*
X-940675Y-472750D01*
X-940525Y-471667D01*
X-940300Y-471083D01*
X-939925Y-470500D01*
X-939400Y-470083D01*
X-938875Y-470000D01*
X-938350Y-470167D01*
X-937975Y-470583D01*
G01X-934900Y-474000D02*
X-934450Y-474583D01*
X-933850Y-474917D01*
X-933175Y-475000D01*
X-932575Y-474917D01*
X-931975Y-474500D01*
X-931600Y-474000D01*
X-931525Y-473500D01*
X-931675Y-472917D01*
X-932200Y-472500D01*
X-932725Y-472333D01*
X-933400D01*
G01X-932725D02*
X-932275Y-472083D01*
X-931900Y-471667D01*
X-931750Y-471167D01*
X-931900Y-470667D01*
X-932275Y-470250D01*
X-932950Y-470000D01*
X-933625Y-470083D01*
X-934300Y-470417D01*
G01X-928525Y-474417D02*
X-928000Y-474833D01*
X-927400Y-475000D01*
X-926800Y-474833D01*
X-926275Y-474333D01*
X-925900Y-473583D01*
X-925750Y-472833D01*
Y-471917D01*
X-925900Y-471167D01*
X-926275Y-470500D01*
X-926725Y-470167D01*
X-927250Y-470000D01*
X-927850Y-470167D01*
X-928300Y-470500D01*
X-928600Y-471000D01*
X-928750Y-471667D01*
X-928600Y-472250D01*
X-928225Y-472833D01*
X-927775Y-473167D01*
X-927250Y-473250D01*
X-926650Y-473083D01*
X-926200Y-472667D01*
X-925750Y-471917D01*
G01X-922525Y-474417D02*
X-922000Y-474833D01*
X-921400Y-475000D01*
X-920800Y-474833D01*
X-920275Y-474333D01*
X-919900Y-473583D01*
X-919750Y-472833D01*
Y-471917D01*
X-919900Y-471167D01*
X-920275Y-470500D01*
X-920725Y-470167D01*
X-921250Y-470000D01*
X-921850Y-470167D01*
X-922300Y-470500D01*
X-922600Y-471000D01*
X-922750Y-471667D01*
X-922600Y-472250D01*
X-922225Y-472833D01*
X-921775Y-473167D01*
X-921250Y-473250D01*
X-920650Y-473083D01*
X-920200Y-472667D01*
X-919750Y-471917D01*
G01X-1006750Y-465000D02*
Y-460000D01*
X-1004875D01*
X-1004275Y-460250D01*
X-1003900Y-460583D01*
X-1003750Y-461250D01*
X-1003900Y-461917D01*
X-1004350Y-462333D01*
X-1004875Y-462583D01*
X-1006750D01*
G01X-1004875D02*
X-1003750Y-465000D01*
G01X-997750D02*
X-1000750D01*
Y-460000D01*
X-997750D01*
G01X-998950Y-462417D02*
X-1000750D01*
G01X-994900Y-465000D02*
Y-460000D01*
X-993400D01*
X-992800Y-460250D01*
X-992350Y-460583D01*
X-991975Y-461083D01*
X-991675Y-461667D01*
X-991600Y-462500D01*
X-991675Y-463333D01*
X-991975Y-463917D01*
X-992350Y-464417D01*
X-992800Y-464750D01*
X-993400Y-465000D01*
X-994900D01*
G01X-989200D02*
Y-460000D01*
X-987250Y-464167D01*
X-985300Y-460000D01*
Y-465000D01*
G01X-981250D02*
X-981850Y-464917D01*
X-982375Y-464583D01*
X-982825Y-464083D01*
X-983125Y-463500D01*
X-983275Y-462833D01*
Y-462167D01*
X-983125Y-461500D01*
X-982825Y-460917D01*
X-982375Y-460417D01*
X-981850Y-460083D01*
X-981250Y-460000D01*
X-980650Y-460083D01*
X-980125Y-460417D01*
X-979675Y-460917D01*
X-979375Y-461500D01*
X-979225Y-462167D01*
Y-462833D01*
X-979375Y-463500D01*
X-979675Y-464083D01*
X-980125Y-464583D01*
X-980650Y-464917D01*
X-981250Y-465000D01*
G01X-976975D02*
Y-460000D01*
X-973525Y-465000D01*
Y-460000D01*
G01X-970900Y-465000D02*
Y-460000D01*
X-969400D01*
X-968800Y-460250D01*
X-968350Y-460583D01*
X-967975Y-461083D01*
X-967675Y-461667D01*
X-967600Y-462500D01*
X-967675Y-463333D01*
X-967975Y-463917D01*
X-968350Y-464417D01*
X-968800Y-464750D01*
X-969400Y-465000D01*
X-970900D01*
G01X-1005250Y-455000D02*
Y-450000D01*
X-1006150Y-451000D01*
G01Y-455000D02*
X-1004350D01*
G01X-995200D02*
Y-450000D01*
X-993250Y-454167D01*
X-991300Y-450000D01*
Y-455000D01*
G01X-988150Y-450000D02*
X-986350D01*
G01X-987250D02*
Y-455000D01*
G01X-988150D02*
X-986350D01*
G01X-979600Y-450417D02*
X-980050Y-450167D01*
X-980575Y-450000D01*
X-981175D01*
X-981850Y-450250D01*
X-982375Y-450667D01*
X-982750Y-451167D01*
X-983050Y-452000D01*
X-983125Y-452750D01*
X-982975Y-453500D01*
X-982750Y-454000D01*
X-982300Y-454500D01*
X-981775Y-454833D01*
X-981250Y-455000D01*
X-980725D01*
X-980200Y-454833D01*
X-979750Y-454583D01*
X-979375Y-454250D01*
G01X-976750Y-455000D02*
Y-450000D01*
X-974875D01*
X-974275Y-450250D01*
X-973900Y-450583D01*
X-973750Y-451250D01*
X-973900Y-451917D01*
X-974350Y-452333D01*
X-974875Y-452583D01*
X-976750D01*
G01X-974875D02*
X-973750Y-455000D01*
G01X-969250D02*
X-969850Y-454917D01*
X-970375Y-454583D01*
X-970825Y-454083D01*
X-971125Y-453500D01*
X-971275Y-452833D01*
Y-452167D01*
X-971125Y-451500D01*
X-970825Y-450917D01*
X-970375Y-450417D01*
X-969850Y-450083D01*
X-969250Y-450000D01*
X-968650Y-450083D01*
X-968125Y-450417D01*
X-967675Y-450917D01*
X-967375Y-451500D01*
X-967225Y-452167D01*
Y-452833D01*
X-967375Y-453500D01*
X-967675Y-454083D01*
X-968125Y-454583D01*
X-968650Y-454917D01*
X-969250Y-455000D01*
G01X-964825Y-454333D02*
X-964225Y-454750D01*
X-963550Y-455000D01*
X-962950D01*
X-962350Y-454750D01*
X-961900Y-454333D01*
X-961675Y-453750D01*
X-961825Y-453167D01*
X-962200Y-452667D01*
X-962875Y-452333D01*
X-963775Y-452167D01*
X-964300Y-451833D01*
X-964525Y-451250D01*
X-964375Y-450667D01*
X-964000Y-450250D01*
X-963475Y-450000D01*
X-962950D01*
X-962425Y-450167D01*
X-961975Y-450583D01*
G01X-957250Y-455000D02*
X-957850Y-454917D01*
X-958375Y-454583D01*
X-958825Y-454083D01*
X-959125Y-453500D01*
X-959275Y-452833D01*
Y-452167D01*
X-959125Y-451500D01*
X-958825Y-450917D01*
X-958375Y-450417D01*
X-957850Y-450083D01*
X-957250Y-450000D01*
X-956650Y-450083D01*
X-956125Y-450417D01*
X-955675Y-450917D01*
X-955375Y-451500D01*
X-955225Y-452167D01*
Y-452833D01*
X-955375Y-453500D01*
X-955675Y-454083D01*
X-956125Y-454583D01*
X-956650Y-454917D01*
X-957250Y-455000D01*
G01X-952675D02*
Y-450000D01*
X-949825D01*
G01X-950875Y-452417D02*
X-952675D01*
G01X-945250Y-450000D02*
Y-455000D01*
G01X-946975Y-450000D02*
X-943525D01*
G01X-935500D02*
X-934450Y-455000D01*
X-933250Y-450000D01*
X-932050Y-455000D01*
X-931000Y-450000D01*
G01X-929125Y-455000D02*
X-927250Y-450000D01*
X-925375Y-455000D01*
G01X-926050Y-453250D02*
X-928450D01*
G01X-921250Y-455000D02*
Y-452750D01*
X-922750Y-450000D01*
G01X-919750D02*
X-921250Y-452750D01*
G54D16*
G01X-874510Y-499000D02*
Y-493000D01*
X-871290Y-499000D01*
Y-493000D01*
G01X-867200Y-499000D02*
X-867760Y-498900D01*
X-868250Y-498500D01*
X-868670Y-497900D01*
X-868950Y-497200D01*
X-869090Y-496400D01*
Y-495600D01*
X-868950Y-494800D01*
X-868670Y-494100D01*
X-868250Y-493500D01*
X-867760Y-493100D01*
X-867200Y-493000D01*
X-866640Y-493100D01*
X-866150Y-493500D01*
X-865730Y-494100D01*
X-865450Y-494800D01*
X-865310Y-495600D01*
Y-496400D01*
X-865450Y-497200D01*
X-865730Y-497900D01*
X-866150Y-498500D01*
X-866640Y-498900D01*
X-867200Y-499000D01*
G01X-861500Y-493000D02*
Y-499000D01*
G01X-863110Y-493000D02*
X-859890D01*
G01X-856640D02*
X-854960D01*
G01X-855800D02*
Y-499000D01*
G01X-856640D02*
X-854960D01*
G01X-848560Y-493500D02*
X-848980Y-493200D01*
X-849470Y-493000D01*
X-850030D01*
X-850660Y-493300D01*
X-851150Y-493800D01*
X-851500Y-494400D01*
X-851780Y-495400D01*
X-851850Y-496300D01*
X-851710Y-497200D01*
X-851500Y-497800D01*
X-851080Y-498400D01*
X-850590Y-498800D01*
X-850100Y-499000D01*
X-849610D01*
X-849120Y-498800D01*
X-848700Y-498500D01*
X-848350Y-498100D01*
G01X-843000Y-499000D02*
X-845800D01*
Y-493000D01*
X-843000D01*
G01X-844120Y-495900D02*
X-845800D01*
G01X-833000Y-499000D02*
X-833560Y-498900D01*
X-834050Y-498500D01*
X-834470Y-497900D01*
X-834750Y-497200D01*
X-834890Y-496400D01*
Y-495600D01*
X-834750Y-494800D01*
X-834470Y-494100D01*
X-834050Y-493500D01*
X-833560Y-493100D01*
X-833000Y-493000D01*
X-832440Y-493100D01*
X-831950Y-493500D01*
X-831530Y-494100D01*
X-831250Y-494800D01*
X-831110Y-495600D01*
Y-496400D01*
X-831250Y-497200D01*
X-831530Y-497900D01*
X-831950Y-498500D01*
X-832440Y-498900D01*
X-833000Y-499000D01*
G01X-828630D02*
Y-493000D01*
X-825970D01*
G01X-826950Y-495900D02*
X-828630D01*
G01X-817300Y-499000D02*
Y-493000D01*
X-815620D01*
X-815060Y-493300D01*
X-814640Y-494000D01*
X-814500Y-494800D01*
X-814640Y-495600D01*
X-814990Y-496200D01*
X-815620Y-496500D01*
X-817300D01*
G01X-811600Y-499000D02*
Y-493000D01*
X-809850D01*
X-809290Y-493300D01*
X-808940Y-493700D01*
X-808800Y-494500D01*
X-808940Y-495300D01*
X-809360Y-495800D01*
X-809850Y-496100D01*
X-811600D01*
G01X-809850D02*
X-808800Y-499000D01*
G01X-804500D02*
X-805060Y-498900D01*
X-805550Y-498500D01*
X-805970Y-497900D01*
X-806250Y-497200D01*
X-806390Y-496400D01*
Y-495600D01*
X-806250Y-494800D01*
X-805970Y-494100D01*
X-805550Y-493500D01*
X-805060Y-493100D01*
X-804500Y-493000D01*
X-803940Y-493100D01*
X-803450Y-493500D01*
X-803030Y-494100D01*
X-802750Y-494800D01*
X-802610Y-495600D01*
Y-496400D01*
X-802750Y-497200D01*
X-803030Y-497900D01*
X-803450Y-498500D01*
X-803940Y-498900D01*
X-804500Y-499000D01*
G01X-800200D02*
Y-493000D01*
X-798520D01*
X-797960Y-493300D01*
X-797540Y-494000D01*
X-797400Y-494800D01*
X-797540Y-495600D01*
X-797890Y-496200D01*
X-798520Y-496500D01*
X-800200D01*
G01X-794500Y-499000D02*
Y-493000D01*
X-792750D01*
X-792190Y-493300D01*
X-791840Y-493700D01*
X-791700Y-494500D01*
X-791840Y-495300D01*
X-792260Y-495800D01*
X-792750Y-496100D01*
X-794500D01*
G01X-792750D02*
X-791700Y-499000D01*
G01X-788240Y-493000D02*
X-786560D01*
G01X-787400D02*
Y-499000D01*
G01X-788240D02*
X-786560D01*
G01X-780300D02*
X-783100D01*
Y-493000D01*
X-780300D01*
G01X-781420Y-495900D02*
X-783100D01*
G01X-776000Y-493000D02*
Y-499000D01*
G01X-777610Y-493000D02*
X-774390D01*
G01X-772050Y-499000D02*
X-770300Y-493000D01*
X-768550Y-499000D01*
G01X-769180Y-496900D02*
X-771420D01*
G01X-766000Y-499000D02*
Y-493000D01*
X-764250D01*
X-763690Y-493300D01*
X-763340Y-493700D01*
X-763200Y-494500D01*
X-763340Y-495300D01*
X-763760Y-495800D01*
X-764250Y-496100D01*
X-766000D01*
G01X-764250D02*
X-763200Y-499000D01*
G01X-758900D02*
Y-496300D01*
X-760300Y-493000D01*
G01X-757500D02*
X-758900Y-496300D01*
G01X-748900Y-499000D02*
Y-493000D01*
X-747220D01*
X-746660Y-493300D01*
X-746240Y-494000D01*
X-746100Y-494800D01*
X-746240Y-495600D01*
X-746590Y-496200D01*
X-747220Y-496500D01*
X-748900D01*
G01X-743200Y-499000D02*
Y-493000D01*
X-741450D01*
X-740890Y-493300D01*
X-740540Y-493700D01*
X-740400Y-494500D01*
X-740540Y-495300D01*
X-740960Y-495800D01*
X-741450Y-496100D01*
X-743200D01*
G01X-741450D02*
X-740400Y-499000D01*
G01X-736100D02*
X-736660Y-498900D01*
X-737150Y-498500D01*
X-737570Y-497900D01*
X-737850Y-497200D01*
X-737990Y-496400D01*
Y-495600D01*
X-737850Y-494800D01*
X-737570Y-494100D01*
X-737150Y-493500D01*
X-736660Y-493100D01*
X-736100Y-493000D01*
X-735540Y-493100D01*
X-735050Y-493500D01*
X-734630Y-494100D01*
X-734350Y-494800D01*
X-734210Y-495600D01*
Y-496400D01*
X-734350Y-497200D01*
X-734630Y-497900D01*
X-735050Y-498500D01*
X-735540Y-498900D01*
X-736100Y-499000D01*
G01X-731800D02*
Y-493000D01*
X-730120D01*
X-729560Y-493300D01*
X-729140Y-494000D01*
X-729000Y-494800D01*
X-729140Y-495600D01*
X-729490Y-496200D01*
X-730120Y-496500D01*
X-731800D01*
G01X-723300Y-499000D02*
X-726100D01*
Y-493000D01*
X-723300D01*
G01X-724420Y-495900D02*
X-726100D01*
G01X-720400Y-499000D02*
Y-493000D01*
X-718650D01*
X-718090Y-493300D01*
X-717740Y-493700D01*
X-717600Y-494500D01*
X-717740Y-495300D01*
X-718160Y-495800D01*
X-718650Y-496100D01*
X-720400D01*
G01X-718650D02*
X-717600Y-499000D01*
G01X-713300Y-493000D02*
Y-499000D01*
G01X-714910Y-493000D02*
X-711690D01*
G01X-707600Y-499000D02*
Y-496300D01*
X-709000Y-493000D01*
G01X-706200D02*
X-707600Y-496300D01*
G01X-701900Y-499200D02*
X-702040Y-499100D01*
Y-498900D01*
X-701900Y-498800D01*
X-701760Y-498900D01*
Y-499100D01*
X-701900Y-499200D01*
G01Y-496500D02*
X-702040Y-496400D01*
Y-496200D01*
X-701900Y-496100D01*
X-701760Y-496200D01*
Y-496400D01*
X-701900Y-496500D01*
G54D17*
G01X-1189333Y-572500D02*
Y-565500D01*
X-1187667D01*
X-1187000Y-565850D01*
X-1186500Y-566317D01*
X-1186083Y-567017D01*
X-1185750Y-567833D01*
X-1185667Y-569000D01*
X-1185750Y-570167D01*
X-1186083Y-570983D01*
X-1186500Y-571684D01*
X-1187000Y-572150D01*
X-1187667Y-572500D01*
X-1189333D01*
G01X-1180700D02*
X-1181367Y-572383D01*
X-1181950Y-571917D01*
X-1182450Y-571217D01*
X-1182783Y-570400D01*
X-1182950Y-569467D01*
Y-568533D01*
X-1182783Y-567600D01*
X-1182450Y-566783D01*
X-1181950Y-566083D01*
X-1181367Y-565617D01*
X-1180700Y-565500D01*
X-1180033Y-565617D01*
X-1179450Y-566083D01*
X-1178950Y-566783D01*
X-1178617Y-567600D01*
X-1178450Y-568533D01*
Y-569467D01*
X-1178617Y-570400D01*
X-1178950Y-571217D01*
X-1179450Y-571917D01*
X-1180033Y-572383D01*
X-1180700Y-572500D01*
G01X-1172067Y-566083D02*
X-1172567Y-565733D01*
X-1173150Y-565500D01*
X-1173817D01*
X-1174567Y-565850D01*
X-1175150Y-566433D01*
X-1175567Y-567133D01*
X-1175900Y-568300D01*
X-1175983Y-569350D01*
X-1175817Y-570400D01*
X-1175567Y-571100D01*
X-1175067Y-571800D01*
X-1174483Y-572267D01*
X-1173900Y-572500D01*
X-1173317D01*
X-1172733Y-572267D01*
X-1172233Y-571917D01*
X-1171817Y-571450D01*
G01X-1168933Y-565500D02*
Y-570517D01*
X-1168600Y-571567D01*
X-1167933Y-572267D01*
X-1167100Y-572500D01*
X-1166267Y-572267D01*
X-1165600Y-571567D01*
X-1165267Y-570517D01*
Y-565500D01*
G01X-1162467Y-572500D02*
Y-565500D01*
X-1160300Y-571333D01*
X-1158133Y-565500D01*
Y-572500D01*
G01X-1151833D02*
X-1155167D01*
Y-565500D01*
X-1151833D01*
G01X-1153167Y-568883D02*
X-1155167D01*
G01X-1148617Y-572500D02*
Y-565500D01*
X-1144783Y-572500D01*
Y-565500D01*
G01X-1139900D02*
Y-572500D01*
G01X-1141817Y-565500D02*
X-1137983D01*
G01X-1128217Y-572500D02*
Y-565500D01*
X-1124383Y-572500D01*
Y-565500D01*
G01X-1121333D02*
Y-570517D01*
X-1121000Y-571567D01*
X-1120333Y-572267D01*
X-1119500Y-572500D01*
X-1118667Y-572267D01*
X-1118000Y-571567D01*
X-1117667Y-570517D01*
Y-565500D01*
G01X-1114867Y-572500D02*
Y-565500D01*
X-1112700Y-571333D01*
X-1110533Y-565500D01*
Y-572500D01*
G01X-1105233Y-568767D02*
X-1104900Y-568417D01*
X-1104650Y-567833D01*
X-1104483Y-567017D01*
X-1104650Y-566317D01*
X-1104983Y-565850D01*
X-1105567Y-565500D01*
X-1107817D01*
Y-572500D01*
X-1105067D01*
X-1104483Y-572033D01*
X-1104150Y-571333D01*
X-1103983Y-570517D01*
X-1104150Y-569700D01*
X-1104650Y-569000D01*
X-1105233Y-568767D01*
X-1107817D01*
G01X-1097433Y-572500D02*
X-1100767D01*
Y-565500D01*
X-1097433D01*
G01X-1098767Y-568883D02*
X-1100767D01*
G01X-1093967Y-572500D02*
Y-565500D01*
X-1091883D01*
X-1091217Y-565850D01*
X-1090800Y-566317D01*
X-1090633Y-567250D01*
X-1090800Y-568183D01*
X-1091300Y-568767D01*
X-1091883Y-569117D01*
X-1093967D01*
G01X-1091883D02*
X-1090633Y-572500D01*
G01X-1189250Y-531567D02*
X-1188583Y-532150D01*
X-1187833Y-532500D01*
X-1187167D01*
X-1186500Y-532150D01*
X-1186000Y-531567D01*
X-1185750Y-530750D01*
X-1185917Y-529933D01*
X-1186333Y-529233D01*
X-1187083Y-528767D01*
X-1188083Y-528533D01*
X-1188667Y-528067D01*
X-1188917Y-527250D01*
X-1188750Y-526433D01*
X-1188333Y-525850D01*
X-1187750Y-525500D01*
X-1187167D01*
X-1186583Y-525733D01*
X-1186083Y-526317D01*
G01X-1182450Y-532500D02*
Y-525500D01*
G01X-1178950D02*
Y-532500D01*
G01Y-529000D02*
X-1182450D01*
G01X-1172233Y-532500D02*
X-1175567D01*
Y-525500D01*
X-1172233D01*
G01X-1173567Y-528883D02*
X-1175567D01*
G01X-1165433Y-532500D02*
X-1168767D01*
Y-525500D01*
X-1165433D01*
G01X-1166767Y-528883D02*
X-1168767D01*
G01X-1160300Y-525500D02*
Y-532500D01*
G01X-1162217Y-525500D02*
X-1158383D01*
G01X-1146700D02*
Y-532500D01*
G01X-1148617Y-525500D02*
X-1144783D01*
G01X-1140900D02*
X-1138900D01*
G01X-1139900D02*
Y-532500D01*
G01X-1140900D02*
X-1138900D01*
G01X-1133100Y-525500D02*
Y-532500D01*
G01X-1135017Y-525500D02*
X-1131183D01*
G01X-1127967D02*
Y-532500D01*
X-1124633D01*
G01X-1117833D02*
X-1121167D01*
Y-525500D01*
X-1117833D01*
G01X-1119167Y-528883D02*
X-1121167D01*
G01X-1112700Y-532733D02*
X-1112867Y-532617D01*
Y-532383D01*
X-1112700Y-532267D01*
X-1112533Y-532383D01*
Y-532617D01*
X-1112700Y-532733D01*
G01Y-529584D02*
X-1112867Y-529467D01*
Y-529233D01*
X-1112700Y-529117D01*
X-1112533Y-529233D01*
Y-529467D01*
X-1112700Y-529584D01*
G01X-1187500Y-485500D02*
Y-492500D01*
G01X-1189417Y-485500D02*
X-1185583D01*
G01X-1181700D02*
X-1179700D01*
G01X-1180700D02*
Y-492500D01*
G01X-1181700D02*
X-1179700D01*
G01X-1173900Y-485500D02*
Y-492500D01*
G01X-1175817Y-485500D02*
X-1171983D01*
G01X-1168767D02*
Y-492500D01*
X-1165433D01*
G01X-1158633D02*
X-1161967D01*
Y-485500D01*
X-1158633D01*
G01X-1159967Y-488883D02*
X-1161967D01*
G01X-916667Y-570000D02*
Y-563000D01*
X-914583D01*
X-913917Y-563350D01*
X-913500Y-563817D01*
X-913333Y-564750D01*
X-913500Y-565683D01*
X-914000Y-566267D01*
X-914583Y-566617D01*
X-916667D01*
G01X-914583D02*
X-913333Y-570000D01*
G01X-906533D02*
X-909867D01*
Y-563000D01*
X-906533D01*
G01X-907867Y-566383D02*
X-909867D01*
G01X-903483Y-563000D02*
X-901400Y-570000D01*
X-899317Y-563000D01*
G01X-907850Y-451567D02*
X-907183Y-452150D01*
X-906433Y-452500D01*
X-905767D01*
X-905100Y-452150D01*
X-904600Y-451567D01*
X-904350Y-450750D01*
X-904517Y-449933D01*
X-904933Y-449233D01*
X-905683Y-448767D01*
X-906683Y-448533D01*
X-907267Y-448067D01*
X-907517Y-447250D01*
X-907350Y-446433D01*
X-906933Y-445850D01*
X-906350Y-445500D01*
X-905767D01*
X-905183Y-445733D01*
X-904683Y-446317D01*
G01X-897467Y-446083D02*
X-897967Y-445733D01*
X-898550Y-445500D01*
X-899217D01*
X-899967Y-445850D01*
X-900550Y-446433D01*
X-900967Y-447133D01*
X-901300Y-448300D01*
X-901383Y-449350D01*
X-901217Y-450400D01*
X-900967Y-451100D01*
X-900467Y-451800D01*
X-899883Y-452267D01*
X-899300Y-452500D01*
X-898717D01*
X-898133Y-452267D01*
X-897633Y-451917D01*
X-897217Y-451450D01*
G01X-894583Y-452500D02*
X-892500Y-445500D01*
X-890417Y-452500D01*
G01X-891167Y-450050D02*
X-893833D01*
G01X-887367Y-445500D02*
Y-452500D01*
X-884033D01*
G01X-877233D02*
X-880567D01*
Y-445500D01*
X-877233D01*
G01X-878567Y-448883D02*
X-880567D01*
G01X-874333Y-572500D02*
Y-565500D01*
X-872667D01*
X-872000Y-565850D01*
X-871500Y-566317D01*
X-871083Y-567017D01*
X-870750Y-567833D01*
X-870667Y-569000D01*
X-870750Y-570167D01*
X-871083Y-570983D01*
X-871500Y-571684D01*
X-872000Y-572150D01*
X-872667Y-572500D01*
X-874333D01*
G01X-866700Y-565500D02*
X-864700D01*
G01X-865700D02*
Y-572500D01*
G01X-866700D02*
X-864700D01*
G01X-860650Y-571567D02*
X-859983Y-572150D01*
X-859233Y-572500D01*
X-858567D01*
X-857900Y-572150D01*
X-857400Y-571567D01*
X-857150Y-570750D01*
X-857317Y-569933D01*
X-857733Y-569233D01*
X-858483Y-568767D01*
X-859483Y-568533D01*
X-860067Y-568067D01*
X-860317Y-567250D01*
X-860150Y-566433D01*
X-859733Y-565850D01*
X-859150Y-565500D01*
X-858567D01*
X-857983Y-565733D01*
X-857483Y-566317D01*
G01X-850267Y-566083D02*
X-850767Y-565733D01*
X-851350Y-565500D01*
X-852017D01*
X-852767Y-565850D01*
X-853350Y-566433D01*
X-853767Y-567133D01*
X-854100Y-568300D01*
X-854183Y-569350D01*
X-854017Y-570400D01*
X-853767Y-571100D01*
X-853267Y-571800D01*
X-852683Y-572267D01*
X-852100Y-572500D01*
X-851517D01*
X-850933Y-572267D01*
X-850433Y-571917D01*
X-850017Y-571450D01*
G01X-846967Y-565500D02*
Y-572500D01*
X-843633D01*
G01X-838500D02*
X-839167Y-572383D01*
X-839750Y-571917D01*
X-840250Y-571217D01*
X-840583Y-570400D01*
X-840750Y-569467D01*
Y-568533D01*
X-840583Y-567600D01*
X-840250Y-566783D01*
X-839750Y-566083D01*
X-839167Y-565617D01*
X-838500Y-565500D01*
X-837833Y-565617D01*
X-837250Y-566083D01*
X-836750Y-566783D01*
X-836417Y-567600D01*
X-836250Y-568533D01*
Y-569467D01*
X-836417Y-570400D01*
X-836750Y-571217D01*
X-837250Y-571917D01*
X-837833Y-572383D01*
X-838500Y-572500D01*
G01X-833450Y-571567D02*
X-832783Y-572150D01*
X-832033Y-572500D01*
X-831367D01*
X-830700Y-572150D01*
X-830200Y-571567D01*
X-829950Y-570750D01*
X-830117Y-569933D01*
X-830533Y-569233D01*
X-831283Y-568767D01*
X-832283Y-568533D01*
X-832867Y-568067D01*
X-833117Y-567250D01*
X-832950Y-566433D01*
X-832533Y-565850D01*
X-831950Y-565500D01*
X-831367D01*
X-830783Y-565733D01*
X-830283Y-566317D01*
G01X-823233Y-572500D02*
X-826567D01*
Y-565500D01*
X-823233D01*
G01X-824567Y-568883D02*
X-826567D01*
G01X-819933Y-572500D02*
Y-565500D01*
X-818267D01*
X-817600Y-565850D01*
X-817100Y-566317D01*
X-816683Y-567017D01*
X-816350Y-567833D01*
X-816267Y-569000D01*
X-816350Y-570167D01*
X-816683Y-570983D01*
X-817100Y-571684D01*
X-817600Y-572150D01*
X-818267Y-572500D01*
X-819933D01*
G01X-807000Y-565500D02*
X-805833Y-572500D01*
X-804500Y-565500D01*
X-803167Y-572500D01*
X-802000Y-565500D01*
G01X-798700D02*
X-796700D01*
G01X-797700D02*
Y-572500D01*
G01X-798700D02*
X-796700D01*
G01X-790900Y-565500D02*
Y-572500D01*
G01X-792817Y-565500D02*
X-788983D01*
G01X-785850Y-572500D02*
Y-565500D01*
G01X-782350D02*
Y-572500D01*
G01Y-569000D02*
X-785850D01*
G01X-777300Y-572500D02*
X-777967Y-572383D01*
X-778550Y-571917D01*
X-779050Y-571217D01*
X-779383Y-570400D01*
X-779550Y-569467D01*
Y-568533D01*
X-779383Y-567600D01*
X-779050Y-566783D01*
X-778550Y-566083D01*
X-777967Y-565617D01*
X-777300Y-565500D01*
X-776633Y-565617D01*
X-776050Y-566083D01*
X-775550Y-566783D01*
X-775217Y-567600D01*
X-775050Y-568533D01*
Y-569467D01*
X-775217Y-570400D01*
X-775550Y-571217D01*
X-776050Y-571917D01*
X-776633Y-572383D01*
X-777300Y-572500D01*
G01X-772333Y-565500D02*
Y-570517D01*
X-772000Y-571567D01*
X-771333Y-572267D01*
X-770500Y-572500D01*
X-769667Y-572267D01*
X-769000Y-571567D01*
X-768667Y-570517D01*
Y-565500D01*
G01X-763700D02*
Y-572500D01*
G01X-765617Y-565500D02*
X-761783D01*
G01X-750100D02*
Y-572500D01*
G01X-752017Y-565500D02*
X-748183D01*
G01X-745050Y-572500D02*
Y-565500D01*
G01X-741550D02*
Y-572500D01*
G01Y-569000D02*
X-745050D01*
G01X-734833Y-572500D02*
X-738167D01*
Y-565500D01*
X-734833D01*
G01X-736167Y-568883D02*
X-738167D01*
G01X-724567Y-572500D02*
Y-565500D01*
X-722567D01*
X-721900Y-565850D01*
X-721400Y-566667D01*
X-721233Y-567600D01*
X-721400Y-568533D01*
X-721817Y-569233D01*
X-722567Y-569584D01*
X-724567D01*
G01X-717767Y-572500D02*
Y-565500D01*
X-715683D01*
X-715017Y-565850D01*
X-714600Y-566317D01*
X-714433Y-567250D01*
X-714600Y-568183D01*
X-715100Y-568767D01*
X-715683Y-569117D01*
X-717767D01*
G01X-715683D02*
X-714433Y-572500D01*
G01X-710300Y-565500D02*
X-708300D01*
G01X-709300D02*
Y-572500D01*
G01X-710300D02*
X-708300D01*
G01X-702500D02*
X-703167Y-572383D01*
X-703750Y-571917D01*
X-704250Y-571217D01*
X-704583Y-570400D01*
X-704750Y-569467D01*
Y-568533D01*
X-704583Y-567600D01*
X-704250Y-566783D01*
X-703750Y-566083D01*
X-703167Y-565617D01*
X-702500Y-565500D01*
X-701833Y-565617D01*
X-701250Y-566083D01*
X-700750Y-566783D01*
X-700417Y-567600D01*
X-700250Y-568533D01*
Y-569467D01*
X-700417Y-570400D01*
X-700750Y-571217D01*
X-701250Y-571917D01*
X-701833Y-572383D01*
X-702500Y-572500D01*
G01X-697367D02*
Y-565500D01*
X-695283D01*
X-694617Y-565850D01*
X-694200Y-566317D01*
X-694033Y-567250D01*
X-694200Y-568183D01*
X-694700Y-568767D01*
X-695283Y-569117D01*
X-697367D01*
G01X-695283D02*
X-694033Y-572500D01*
G01X-684600Y-565500D02*
X-683433Y-572500D01*
X-682100Y-565500D01*
X-680767Y-572500D01*
X-679600Y-565500D01*
G01X-676967Y-572500D02*
Y-565500D01*
X-674883D01*
X-674217Y-565850D01*
X-673800Y-566317D01*
X-673633Y-567250D01*
X-673800Y-568183D01*
X-674300Y-568767D01*
X-674883Y-569117D01*
X-676967D01*
G01X-674883D02*
X-673633Y-572500D01*
G01X-669500Y-565500D02*
X-667500D01*
G01X-668500D02*
Y-572500D01*
G01X-669500D02*
X-667500D01*
G01X-661700Y-565500D02*
Y-572500D01*
G01X-663617Y-565500D02*
X-659783D01*
G01X-654900D02*
Y-572500D01*
G01X-656817Y-565500D02*
X-652983D01*
G01X-646433Y-572500D02*
X-649767D01*
Y-565500D01*
X-646433D01*
G01X-647767Y-568883D02*
X-649767D01*
G01X-643217Y-572500D02*
Y-565500D01*
X-639383Y-572500D01*
Y-565500D01*
G01X-625867Y-566083D02*
X-626367Y-565733D01*
X-626950Y-565500D01*
X-627617D01*
X-628367Y-565850D01*
X-628950Y-566433D01*
X-629367Y-567133D01*
X-629700Y-568300D01*
X-629783Y-569350D01*
X-629617Y-570400D01*
X-629367Y-571100D01*
X-628867Y-571800D01*
X-628283Y-572267D01*
X-627700Y-572500D01*
X-627117D01*
X-626533Y-572267D01*
X-626033Y-571917D01*
X-625617Y-571450D01*
G01X-620900Y-572500D02*
X-621567Y-572383D01*
X-622150Y-571917D01*
X-622650Y-571217D01*
X-622983Y-570400D01*
X-623150Y-569467D01*
Y-568533D01*
X-622983Y-567600D01*
X-622650Y-566783D01*
X-622150Y-566083D01*
X-621567Y-565617D01*
X-620900Y-565500D01*
X-620233Y-565617D01*
X-619650Y-566083D01*
X-619150Y-566783D01*
X-618817Y-567600D01*
X-618650Y-568533D01*
Y-569467D01*
X-618817Y-570400D01*
X-619150Y-571217D01*
X-619650Y-571917D01*
X-620233Y-572383D01*
X-620900Y-572500D01*
G01X-616017D02*
Y-565500D01*
X-612183Y-572500D01*
Y-565500D01*
G01X-609050Y-571567D02*
X-608383Y-572150D01*
X-607633Y-572500D01*
X-606967D01*
X-606300Y-572150D01*
X-605800Y-571567D01*
X-605550Y-570750D01*
X-605717Y-569933D01*
X-606133Y-569233D01*
X-606883Y-568767D01*
X-607883Y-568533D01*
X-608467Y-568067D01*
X-608717Y-567250D01*
X-608550Y-566433D01*
X-608133Y-565850D01*
X-607550Y-565500D01*
X-606967D01*
X-606383Y-565733D01*
X-605883Y-566317D01*
G01X-598833Y-572500D02*
X-602167D01*
Y-565500D01*
X-598833D01*
G01X-600167Y-568883D02*
X-602167D01*
G01X-595617Y-572500D02*
Y-565500D01*
X-591783Y-572500D01*
Y-565500D01*
G01X-586900D02*
Y-572500D01*
G01X-588817Y-565500D02*
X-584983D01*
G01X-872500Y-587500D02*
X-873167Y-587383D01*
X-873750Y-586917D01*
X-874250Y-586217D01*
X-874583Y-585400D01*
X-874750Y-584467D01*
Y-583533D01*
X-874583Y-582600D01*
X-874250Y-581783D01*
X-873750Y-581083D01*
X-873167Y-580617D01*
X-872500Y-580500D01*
X-871833Y-580617D01*
X-871250Y-581083D01*
X-870750Y-581783D01*
X-870417Y-582600D01*
X-870250Y-583533D01*
Y-584467D01*
X-870417Y-585400D01*
X-870750Y-586217D01*
X-871250Y-586917D01*
X-871833Y-587383D01*
X-872500Y-587500D01*
G01X-867283D02*
Y-580500D01*
X-864117D01*
G01X-865283Y-583883D02*
X-867283D01*
G01X-854267Y-587500D02*
Y-580500D01*
X-852100Y-586333D01*
X-849933Y-580500D01*
Y-587500D01*
G01X-846300Y-580500D02*
X-844300D01*
G01X-845300D02*
Y-587500D01*
G01X-846300D02*
X-844300D01*
G01X-836667Y-581083D02*
X-837167Y-580733D01*
X-837750Y-580500D01*
X-838417D01*
X-839167Y-580850D01*
X-839750Y-581433D01*
X-840167Y-582133D01*
X-840500Y-583300D01*
X-840583Y-584350D01*
X-840417Y-585400D01*
X-840167Y-586100D01*
X-839667Y-586800D01*
X-839083Y-587267D01*
X-838500Y-587500D01*
X-837917D01*
X-837333Y-587267D01*
X-836833Y-586917D01*
X-836417Y-586450D01*
G01X-833367Y-587500D02*
Y-580500D01*
X-831283D01*
X-830617Y-580850D01*
X-830200Y-581317D01*
X-830033Y-582250D01*
X-830200Y-583183D01*
X-830700Y-583767D01*
X-831283Y-584117D01*
X-833367D01*
G01X-831283D02*
X-830033Y-587500D01*
G01X-824900D02*
X-825567Y-587383D01*
X-826150Y-586917D01*
X-826650Y-586217D01*
X-826983Y-585400D01*
X-827150Y-584467D01*
Y-583533D01*
X-826983Y-582600D01*
X-826650Y-581783D01*
X-826150Y-581083D01*
X-825567Y-580617D01*
X-824900Y-580500D01*
X-824233Y-580617D01*
X-823650Y-581083D01*
X-823150Y-581783D01*
X-822817Y-582600D01*
X-822650Y-583533D01*
Y-584467D01*
X-822817Y-585400D01*
X-823150Y-586217D01*
X-823650Y-586917D01*
X-824233Y-587383D01*
X-824900Y-587500D01*
G01X-819850Y-586567D02*
X-819183Y-587150D01*
X-818433Y-587500D01*
X-817767D01*
X-817100Y-587150D01*
X-816600Y-586567D01*
X-816350Y-585750D01*
X-816517Y-584933D01*
X-816933Y-584233D01*
X-817683Y-583767D01*
X-818683Y-583533D01*
X-819267Y-583067D01*
X-819517Y-582250D01*
X-819350Y-581433D01*
X-818933Y-580850D01*
X-818350Y-580500D01*
X-817767D01*
X-817183Y-580733D01*
X-816683Y-581317D01*
G01X-811300Y-587500D02*
X-811967Y-587383D01*
X-812550Y-586917D01*
X-813050Y-586217D01*
X-813383Y-585400D01*
X-813550Y-584467D01*
Y-583533D01*
X-813383Y-582600D01*
X-813050Y-581783D01*
X-812550Y-581083D01*
X-811967Y-580617D01*
X-811300Y-580500D01*
X-810633Y-580617D01*
X-810050Y-581083D01*
X-809550Y-581783D01*
X-809217Y-582600D01*
X-809050Y-583533D01*
Y-584467D01*
X-809217Y-585400D01*
X-809550Y-586217D01*
X-810050Y-586917D01*
X-810633Y-587383D01*
X-811300Y-587500D01*
G01X-806083D02*
Y-580500D01*
X-802917D01*
G01X-804083Y-583883D02*
X-806083D01*
G01X-797700Y-580500D02*
Y-587500D01*
G01X-799617Y-580500D02*
X-795783D01*
G01X-782267Y-581083D02*
X-782767Y-580733D01*
X-783350Y-580500D01*
X-784017D01*
X-784767Y-580850D01*
X-785350Y-581433D01*
X-785767Y-582133D01*
X-786100Y-583300D01*
X-786183Y-584350D01*
X-786017Y-585400D01*
X-785767Y-586100D01*
X-785267Y-586800D01*
X-784683Y-587267D01*
X-784100Y-587500D01*
X-783517D01*
X-782933Y-587267D01*
X-782433Y-586917D01*
X-782017Y-586450D01*
G01X-777300Y-587500D02*
X-777967Y-587383D01*
X-778550Y-586917D01*
X-779050Y-586217D01*
X-779383Y-585400D01*
X-779550Y-584467D01*
Y-583533D01*
X-779383Y-582600D01*
X-779050Y-581783D01*
X-778550Y-581083D01*
X-777967Y-580617D01*
X-777300Y-580500D01*
X-776633Y-580617D01*
X-776050Y-581083D01*
X-775550Y-581783D01*
X-775217Y-582600D01*
X-775050Y-583533D01*
Y-584467D01*
X-775217Y-585400D01*
X-775550Y-586217D01*
X-776050Y-586917D01*
X-776633Y-587383D01*
X-777300Y-587500D01*
G01X-772167D02*
Y-580500D01*
X-770083D01*
X-769417Y-580850D01*
X-769000Y-581317D01*
X-768833Y-582250D01*
X-769000Y-583183D01*
X-769500Y-583767D01*
X-770083Y-584117D01*
X-772167D01*
G01X-770083D02*
X-768833Y-587500D01*
G01X-765367D02*
Y-580500D01*
X-763367D01*
X-762700Y-580850D01*
X-762200Y-581667D01*
X-762033Y-582600D01*
X-762200Y-583533D01*
X-762617Y-584233D01*
X-763367Y-584584D01*
X-765367D01*
G01X-756900Y-587500D02*
X-757567Y-587383D01*
X-758150Y-586917D01*
X-758650Y-586217D01*
X-758983Y-585400D01*
X-759150Y-584467D01*
Y-583533D01*
X-758983Y-582600D01*
X-758650Y-581783D01*
X-758150Y-581083D01*
X-757567Y-580617D01*
X-756900Y-580500D01*
X-756233Y-580617D01*
X-755650Y-581083D01*
X-755150Y-581783D01*
X-754817Y-582600D01*
X-754650Y-583533D01*
Y-584467D01*
X-754817Y-585400D01*
X-755150Y-586217D01*
X-755650Y-586917D01*
X-756233Y-587383D01*
X-756900Y-587500D01*
G01X-751767D02*
Y-580500D01*
X-749683D01*
X-749017Y-580850D01*
X-748600Y-581317D01*
X-748433Y-582250D01*
X-748600Y-583183D01*
X-749100Y-583767D01*
X-749683Y-584117D01*
X-751767D01*
G01X-749683D02*
X-748433Y-587500D01*
G01X-745383D02*
X-743300Y-580500D01*
X-741217Y-587500D01*
G01X-741967Y-585050D02*
X-744633D01*
G01X-736500Y-580500D02*
Y-587500D01*
G01X-738417Y-580500D02*
X-734583D01*
G01X-730700D02*
X-728700D01*
G01X-729700D02*
Y-587500D01*
G01X-730700D02*
X-728700D01*
G01X-722900D02*
X-723567Y-587383D01*
X-724150Y-586917D01*
X-724650Y-586217D01*
X-724983Y-585400D01*
X-725150Y-584467D01*
Y-583533D01*
X-724983Y-582600D01*
X-724650Y-581783D01*
X-724150Y-581083D01*
X-723567Y-580617D01*
X-722900Y-580500D01*
X-722233Y-580617D01*
X-721650Y-581083D01*
X-721150Y-581783D01*
X-720817Y-582600D01*
X-720650Y-583533D01*
Y-584467D01*
X-720817Y-585400D01*
X-721150Y-586217D01*
X-721650Y-586917D01*
X-722233Y-587383D01*
X-722900Y-587500D01*
G01X-718017D02*
Y-580500D01*
X-714183Y-587500D01*
Y-580500D01*
G01X-709300Y-587733D02*
X-709467Y-587617D01*
Y-587383D01*
X-709300Y-587267D01*
X-709133Y-587383D01*
Y-587617D01*
X-709300Y-587733D01*
G01X-870667Y-551083D02*
X-871167Y-550733D01*
X-871750Y-550500D01*
X-872417D01*
X-873167Y-550850D01*
X-873750Y-551433D01*
X-874167Y-552133D01*
X-874500Y-553300D01*
X-874583Y-554350D01*
X-874417Y-555400D01*
X-874167Y-556100D01*
X-873667Y-556800D01*
X-873083Y-557267D01*
X-872500Y-557500D01*
X-871917D01*
X-871333Y-557267D01*
X-870833Y-556917D01*
X-870417Y-556450D01*
G01X-865700Y-557500D02*
X-866367Y-557383D01*
X-866950Y-556917D01*
X-867450Y-556217D01*
X-867783Y-555400D01*
X-867950Y-554467D01*
Y-553533D01*
X-867783Y-552600D01*
X-867450Y-551783D01*
X-866950Y-551083D01*
X-866367Y-550617D01*
X-865700Y-550500D01*
X-865033Y-550617D01*
X-864450Y-551083D01*
X-863950Y-551783D01*
X-863617Y-552600D01*
X-863450Y-553533D01*
Y-554467D01*
X-863617Y-555400D01*
X-863950Y-556217D01*
X-864450Y-556917D01*
X-865033Y-557383D01*
X-865700Y-557500D01*
G01X-860817D02*
Y-550500D01*
X-856983Y-557500D01*
Y-550500D01*
G01X-853683Y-557500D02*
Y-550500D01*
X-850517D01*
G01X-851683Y-553883D02*
X-853683D01*
G01X-846300Y-550500D02*
X-844300D01*
G01X-845300D02*
Y-557500D01*
G01X-846300D02*
X-844300D01*
G01X-840333D02*
Y-550500D01*
X-838667D01*
X-838000Y-550850D01*
X-837500Y-551317D01*
X-837083Y-552017D01*
X-836750Y-552833D01*
X-836667Y-554000D01*
X-836750Y-555167D01*
X-837083Y-555983D01*
X-837500Y-556684D01*
X-838000Y-557150D01*
X-838667Y-557500D01*
X-840333D01*
G01X-830033D02*
X-833367D01*
Y-550500D01*
X-830033D01*
G01X-831367Y-553883D02*
X-833367D01*
G01X-826817Y-557500D02*
Y-550500D01*
X-822983Y-557500D01*
Y-550500D01*
G01X-816267Y-551083D02*
X-816767Y-550733D01*
X-817350Y-550500D01*
X-818017D01*
X-818767Y-550850D01*
X-819350Y-551433D01*
X-819767Y-552133D01*
X-820100Y-553300D01*
X-820183Y-554350D01*
X-820017Y-555400D01*
X-819767Y-556100D01*
X-819267Y-556800D01*
X-818683Y-557267D01*
X-818100Y-557500D01*
X-817517D01*
X-816933Y-557267D01*
X-816433Y-556917D01*
X-816017Y-556450D01*
G01X-809633Y-557500D02*
X-812967D01*
Y-550500D01*
X-809633D01*
G01X-810967Y-553883D02*
X-812967D01*
G01X-799783Y-557500D02*
X-797700Y-550500D01*
X-795617Y-557500D01*
G01X-796367Y-555050D02*
X-799033D01*
G01X-792817Y-557500D02*
Y-550500D01*
X-788983Y-557500D01*
Y-550500D01*
G01X-785933Y-557500D02*
Y-550500D01*
X-784267D01*
X-783600Y-550850D01*
X-783100Y-551317D01*
X-782683Y-552017D01*
X-782350Y-552833D01*
X-782267Y-554000D01*
X-782350Y-555167D01*
X-782683Y-555983D01*
X-783100Y-556684D01*
X-783600Y-557150D01*
X-784267Y-557500D01*
X-785933D01*
G01X-771500Y-550500D02*
X-769500D01*
G01X-770500D02*
Y-557500D01*
G01X-771500D02*
X-769500D01*
G01X-763700Y-550500D02*
Y-557500D01*
G01X-765617Y-550500D02*
X-761783D01*
G01X-758650Y-556567D02*
X-757983Y-557150D01*
X-757233Y-557500D01*
X-756567D01*
X-755900Y-557150D01*
X-755400Y-556567D01*
X-755150Y-555750D01*
X-755317Y-554933D01*
X-755733Y-554233D01*
X-756483Y-553767D01*
X-757483Y-553533D01*
X-758067Y-553067D01*
X-758317Y-552250D01*
X-758150Y-551433D01*
X-757733Y-550850D01*
X-757150Y-550500D01*
X-756567D01*
X-755983Y-550733D01*
X-755483Y-551317D01*
G01X-741467Y-551083D02*
X-741967Y-550733D01*
X-742550Y-550500D01*
X-743217D01*
X-743967Y-550850D01*
X-744550Y-551433D01*
X-744967Y-552133D01*
X-745300Y-553300D01*
X-745383Y-554350D01*
X-745217Y-555400D01*
X-744967Y-556100D01*
X-744467Y-556800D01*
X-743883Y-557267D01*
X-743300Y-557500D01*
X-742717D01*
X-742133Y-557267D01*
X-741633Y-556917D01*
X-741217Y-556450D01*
G01X-736500Y-557500D02*
X-737167Y-557383D01*
X-737750Y-556917D01*
X-738250Y-556217D01*
X-738583Y-555400D01*
X-738750Y-554467D01*
Y-553533D01*
X-738583Y-552600D01*
X-738250Y-551783D01*
X-737750Y-551083D01*
X-737167Y-550617D01*
X-736500Y-550500D01*
X-735833Y-550617D01*
X-735250Y-551083D01*
X-734750Y-551783D01*
X-734417Y-552600D01*
X-734250Y-553533D01*
Y-554467D01*
X-734417Y-555400D01*
X-734750Y-556217D01*
X-735250Y-556917D01*
X-735833Y-557383D01*
X-736500Y-557500D01*
G01X-731617D02*
Y-550500D01*
X-727783Y-557500D01*
Y-550500D01*
G01X-722900D02*
Y-557500D01*
G01X-724817Y-550500D02*
X-720983D01*
G01X-714433Y-557500D02*
X-717767D01*
Y-550500D01*
X-714433D01*
G01X-715767Y-553883D02*
X-717767D01*
G01X-711217Y-557500D02*
Y-550500D01*
X-707383Y-557500D01*
Y-550500D01*
G01X-702500D02*
Y-557500D01*
G01X-704417Y-550500D02*
X-700583D01*
G01X-697450Y-556567D02*
X-696783Y-557150D01*
X-696033Y-557500D01*
X-695367D01*
X-694700Y-557150D01*
X-694200Y-556567D01*
X-693950Y-555750D01*
X-694117Y-554933D01*
X-694533Y-554233D01*
X-695283Y-553767D01*
X-696283Y-553533D01*
X-696867Y-553067D01*
X-697117Y-552250D01*
X-696950Y-551433D01*
X-696533Y-550850D01*
X-695950Y-550500D01*
X-695367D01*
X-694783Y-550733D01*
X-694283Y-551317D01*
G01X-684267Y-557500D02*
Y-550500D01*
X-682100Y-556333D01*
X-679933Y-550500D01*
Y-557500D01*
G01X-677383D02*
X-675300Y-550500D01*
X-673217Y-557500D01*
G01X-673967Y-555050D02*
X-676633D01*
G01X-668500Y-557500D02*
Y-554350D01*
X-670167Y-550500D01*
G01X-666833D02*
X-668500Y-554350D01*
G01X-656817Y-557500D02*
Y-550500D01*
X-652983Y-557500D01*
Y-550500D01*
G01X-648100Y-557500D02*
X-648767Y-557383D01*
X-649350Y-556917D01*
X-649850Y-556217D01*
X-650183Y-555400D01*
X-650350Y-554467D01*
Y-553533D01*
X-650183Y-552600D01*
X-649850Y-551783D01*
X-649350Y-551083D01*
X-648767Y-550617D01*
X-648100Y-550500D01*
X-647433Y-550617D01*
X-646850Y-551083D01*
X-646350Y-551783D01*
X-646017Y-552600D01*
X-645850Y-553533D01*
Y-554467D01*
X-646017Y-555400D01*
X-646350Y-556217D01*
X-646850Y-556917D01*
X-647433Y-557383D01*
X-648100Y-557500D01*
G01X-641300Y-550500D02*
Y-557500D01*
G01X-643217Y-550500D02*
X-639383D01*
G01X-627033Y-553767D02*
X-626700Y-553417D01*
X-626450Y-552833D01*
X-626283Y-552017D01*
X-626450Y-551317D01*
X-626783Y-550850D01*
X-627367Y-550500D01*
X-629617D01*
Y-557500D01*
X-626867D01*
X-626283Y-557033D01*
X-625950Y-556333D01*
X-625783Y-555517D01*
X-625950Y-554700D01*
X-626450Y-554000D01*
X-627033Y-553767D01*
X-629617D01*
G01X-619233Y-557500D02*
X-622567D01*
Y-550500D01*
X-619233D01*
G01X-620567Y-553883D02*
X-622567D01*
G01X-870667Y-536083D02*
X-871167Y-535733D01*
X-871750Y-535500D01*
X-872417D01*
X-873167Y-535850D01*
X-873750Y-536433D01*
X-874167Y-537133D01*
X-874500Y-538300D01*
X-874583Y-539350D01*
X-874417Y-540400D01*
X-874167Y-541100D01*
X-873667Y-541800D01*
X-873083Y-542267D01*
X-872500Y-542500D01*
X-871917D01*
X-871333Y-542267D01*
X-870833Y-541917D01*
X-870417Y-541450D01*
G01X-865700Y-542500D02*
X-866367Y-542383D01*
X-866950Y-541917D01*
X-867450Y-541217D01*
X-867783Y-540400D01*
X-867950Y-539467D01*
Y-538533D01*
X-867783Y-537600D01*
X-867450Y-536783D01*
X-866950Y-536083D01*
X-866367Y-535617D01*
X-865700Y-535500D01*
X-865033Y-535617D01*
X-864450Y-536083D01*
X-863950Y-536783D01*
X-863617Y-537600D01*
X-863450Y-538533D01*
Y-539467D01*
X-863617Y-540400D01*
X-863950Y-541217D01*
X-864450Y-541917D01*
X-865033Y-542383D01*
X-865700Y-542500D01*
G01X-860567D02*
Y-535500D01*
X-858483D01*
X-857817Y-535850D01*
X-857400Y-536317D01*
X-857233Y-537250D01*
X-857400Y-538183D01*
X-857900Y-538767D01*
X-858483Y-539117D01*
X-860567D01*
G01X-858483D02*
X-857233Y-542500D01*
G01X-853767D02*
Y-535500D01*
X-851767D01*
X-851100Y-535850D01*
X-850600Y-536667D01*
X-850433Y-537600D01*
X-850600Y-538533D01*
X-851017Y-539233D01*
X-851767Y-539584D01*
X-853767D01*
G01X-845300Y-542500D02*
X-845967Y-542383D01*
X-846550Y-541917D01*
X-847050Y-541217D01*
X-847383Y-540400D01*
X-847550Y-539467D01*
Y-538533D01*
X-847383Y-537600D01*
X-847050Y-536783D01*
X-846550Y-536083D01*
X-845967Y-535617D01*
X-845300Y-535500D01*
X-844633Y-535617D01*
X-844050Y-536083D01*
X-843550Y-536783D01*
X-843217Y-537600D01*
X-843050Y-538533D01*
Y-539467D01*
X-843217Y-540400D01*
X-843550Y-541217D01*
X-844050Y-541917D01*
X-844633Y-542383D01*
X-845300Y-542500D01*
G01X-840167D02*
Y-535500D01*
X-838083D01*
X-837417Y-535850D01*
X-837000Y-536317D01*
X-836833Y-537250D01*
X-837000Y-538183D01*
X-837500Y-538767D01*
X-838083Y-539117D01*
X-840167D01*
G01X-838083D02*
X-836833Y-542500D01*
G01X-833783D02*
X-831700Y-535500D01*
X-829617Y-542500D01*
G01X-830367Y-540050D02*
X-833033D01*
G01X-824900Y-535500D02*
Y-542500D01*
G01X-826817Y-535500D02*
X-822983D01*
G01X-819100D02*
X-817100D01*
G01X-818100D02*
Y-542500D01*
G01X-819100D02*
X-817100D01*
G01X-811300D02*
X-811967Y-542383D01*
X-812550Y-541917D01*
X-813050Y-541217D01*
X-813383Y-540400D01*
X-813550Y-539467D01*
Y-538533D01*
X-813383Y-537600D01*
X-813050Y-536783D01*
X-812550Y-536083D01*
X-811967Y-535617D01*
X-811300Y-535500D01*
X-810633Y-535617D01*
X-810050Y-536083D01*
X-809550Y-536783D01*
X-809217Y-537600D01*
X-809050Y-538533D01*
Y-539467D01*
X-809217Y-540400D01*
X-809550Y-541217D01*
X-810050Y-541917D01*
X-810633Y-542383D01*
X-811300Y-542500D01*
G01X-806417D02*
Y-535500D01*
X-802583Y-542500D01*
Y-535500D01*
G01X-797700Y-542733D02*
X-797867Y-542617D01*
Y-542383D01*
X-797700Y-542267D01*
X-797533Y-542383D01*
Y-542617D01*
X-797700Y-542733D01*
G01X-784100Y-535500D02*
Y-542500D01*
G01X-786017Y-535500D02*
X-782183D01*
G01X-779050Y-542500D02*
Y-535500D01*
G01X-775550D02*
Y-542500D01*
G01Y-539000D02*
X-779050D01*
G01X-771500Y-535500D02*
X-769500D01*
G01X-770500D02*
Y-542500D01*
G01X-771500D02*
X-769500D01*
G01X-765450Y-541567D02*
X-764783Y-542150D01*
X-764033Y-542500D01*
X-763367D01*
X-762700Y-542150D01*
X-762200Y-541567D01*
X-761950Y-540750D01*
X-762117Y-539933D01*
X-762533Y-539233D01*
X-763283Y-538767D01*
X-764283Y-538533D01*
X-764867Y-538067D01*
X-765117Y-537250D01*
X-764950Y-536433D01*
X-764533Y-535850D01*
X-763950Y-535500D01*
X-763367D01*
X-762783Y-535733D01*
X-762283Y-536317D01*
G01X-751933Y-542500D02*
Y-535500D01*
X-750267D01*
X-749600Y-535850D01*
X-749100Y-536317D01*
X-748683Y-537017D01*
X-748350Y-537833D01*
X-748267Y-539000D01*
X-748350Y-540167D01*
X-748683Y-540983D01*
X-749100Y-541684D01*
X-749600Y-542150D01*
X-750267Y-542500D01*
X-751933D01*
G01X-744967D02*
Y-535500D01*
X-742883D01*
X-742217Y-535850D01*
X-741800Y-536317D01*
X-741633Y-537250D01*
X-741800Y-538183D01*
X-742300Y-538767D01*
X-742883Y-539117D01*
X-744967D01*
G01X-742883D02*
X-741633Y-542500D01*
G01X-738583D02*
X-736500Y-535500D01*
X-734417Y-542500D01*
G01X-735167Y-540050D02*
X-737833D01*
G01X-732200Y-535500D02*
X-731033Y-542500D01*
X-729700Y-535500D01*
X-728367Y-542500D01*
X-727200Y-535500D01*
G01X-723900D02*
X-721900D01*
G01X-722900D02*
Y-542500D01*
G01X-723900D02*
X-721900D01*
G01X-718017D02*
Y-535500D01*
X-714183Y-542500D01*
Y-535500D01*
G01X-708800Y-539000D02*
X-707133D01*
Y-541100D01*
X-707633Y-541800D01*
X-708217Y-542267D01*
X-709050Y-542500D01*
X-709883Y-542267D01*
X-710467Y-541800D01*
X-710967Y-541100D01*
X-711300Y-540283D01*
X-711467Y-539350D01*
Y-538533D01*
X-711300Y-537833D01*
X-710967Y-537017D01*
X-710467Y-536317D01*
X-709967Y-535850D01*
X-709300Y-535500D01*
X-708717D01*
X-708050Y-535733D01*
X-707550Y-536200D01*
G01X-696700Y-535500D02*
X-694700D01*
G01X-695700D02*
Y-542500D01*
G01X-696700D02*
X-694700D01*
G01X-690650Y-541567D02*
X-689983Y-542150D01*
X-689233Y-542500D01*
X-688567D01*
X-687900Y-542150D01*
X-687400Y-541567D01*
X-687150Y-540750D01*
X-687317Y-539933D01*
X-687733Y-539233D01*
X-688483Y-538767D01*
X-689483Y-538533D01*
X-690067Y-538067D01*
X-690317Y-537250D01*
X-690150Y-536433D01*
X-689733Y-535850D01*
X-689150Y-535500D01*
X-688567D01*
X-687983Y-535733D01*
X-687483Y-536317D01*
G01X-676967Y-542500D02*
Y-535500D01*
X-674883D01*
X-674217Y-535850D01*
X-673800Y-536317D01*
X-673633Y-537250D01*
X-673800Y-538183D01*
X-674300Y-538767D01*
X-674883Y-539117D01*
X-676967D01*
G01X-674883D02*
X-673633Y-542500D01*
G01X-666833D02*
X-670167D01*
Y-535500D01*
X-666833D01*
G01X-668167Y-538883D02*
X-670167D01*
G01X-659867Y-536083D02*
X-660367Y-535733D01*
X-660950Y-535500D01*
X-661617D01*
X-662367Y-535850D01*
X-662950Y-536433D01*
X-663367Y-537133D01*
X-663700Y-538300D01*
X-663783Y-539350D01*
X-663617Y-540400D01*
X-663367Y-541100D01*
X-662867Y-541800D01*
X-662283Y-542267D01*
X-661700Y-542500D01*
X-661117D01*
X-660533Y-542267D01*
X-660033Y-541917D01*
X-659617Y-541450D01*
G01X-653233Y-542500D02*
X-656567D01*
Y-535500D01*
X-653233D01*
G01X-654567Y-538883D02*
X-656567D01*
G01X-649100Y-535500D02*
X-647100D01*
G01X-648100D02*
Y-542500D01*
G01X-649100D02*
X-647100D01*
G01X-643383Y-535500D02*
X-641300Y-542500D01*
X-639217Y-535500D01*
G01X-632833Y-542500D02*
X-636167D01*
Y-535500D01*
X-632833D01*
G01X-634167Y-538883D02*
X-636167D01*
G01X-629533Y-542500D02*
Y-535500D01*
X-627867D01*
X-627200Y-535850D01*
X-626700Y-536317D01*
X-626283Y-537017D01*
X-625950Y-537833D01*
X-625867Y-539000D01*
X-625950Y-540167D01*
X-626283Y-540983D01*
X-626700Y-541684D01*
X-627200Y-542150D01*
X-627867Y-542500D01*
X-629533D01*
G01X-615100Y-535500D02*
X-613100D01*
G01X-614100D02*
Y-542500D01*
G01X-615100D02*
X-613100D01*
G01X-609217D02*
Y-535500D01*
X-605383Y-542500D01*
Y-535500D01*
G01X-872500Y-520500D02*
Y-527500D01*
G01X-874417Y-520500D02*
X-870583D01*
G01X-867450Y-527500D02*
Y-520500D01*
G01X-863950D02*
Y-527500D01*
G01Y-524000D02*
X-867450D01*
G01X-857233Y-527500D02*
X-860567D01*
Y-520500D01*
X-857233D01*
G01X-858567Y-523883D02*
X-860567D01*
G01X-846967Y-527500D02*
Y-520500D01*
X-844967D01*
X-844300Y-520850D01*
X-843800Y-521667D01*
X-843633Y-522600D01*
X-843800Y-523533D01*
X-844217Y-524233D01*
X-844967Y-524584D01*
X-846967D01*
G01X-840167Y-527500D02*
Y-520500D01*
X-838083D01*
X-837417Y-520850D01*
X-837000Y-521317D01*
X-836833Y-522250D01*
X-837000Y-523183D01*
X-837500Y-523767D01*
X-838083Y-524117D01*
X-840167D01*
G01X-838083D02*
X-836833Y-527500D01*
G01X-831700D02*
X-832367Y-527383D01*
X-832950Y-526917D01*
X-833450Y-526217D01*
X-833783Y-525400D01*
X-833950Y-524467D01*
Y-523533D01*
X-833783Y-522600D01*
X-833450Y-521783D01*
X-832950Y-521083D01*
X-832367Y-520617D01*
X-831700Y-520500D01*
X-831033Y-520617D01*
X-830450Y-521083D01*
X-829950Y-521783D01*
X-829617Y-522600D01*
X-829450Y-523533D01*
Y-524467D01*
X-829617Y-525400D01*
X-829950Y-526217D01*
X-830450Y-526917D01*
X-831033Y-527383D01*
X-831700Y-527500D01*
G01X-826567D02*
Y-520500D01*
X-824567D01*
X-823900Y-520850D01*
X-823400Y-521667D01*
X-823233Y-522600D01*
X-823400Y-523533D01*
X-823817Y-524233D01*
X-824567Y-524584D01*
X-826567D01*
G01X-819767Y-527500D02*
Y-520500D01*
X-817683D01*
X-817017Y-520850D01*
X-816600Y-521317D01*
X-816433Y-522250D01*
X-816600Y-523183D01*
X-817100Y-523767D01*
X-817683Y-524117D01*
X-819767D01*
G01X-817683D02*
X-816433Y-527500D01*
G01X-812300Y-520500D02*
X-810300D01*
G01X-811300D02*
Y-527500D01*
G01X-812300D02*
X-810300D01*
G01X-802833D02*
X-806167D01*
Y-520500D01*
X-802833D01*
G01X-804167Y-523883D02*
X-806167D01*
G01X-797700Y-520500D02*
Y-527500D01*
G01X-799617Y-520500D02*
X-795783D01*
G01X-792983Y-527500D02*
X-790900Y-520500D01*
X-788817Y-527500D01*
G01X-789567Y-525050D02*
X-792233D01*
G01X-785767Y-527500D02*
Y-520500D01*
X-783683D01*
X-783017Y-520850D01*
X-782600Y-521317D01*
X-782433Y-522250D01*
X-782600Y-523183D01*
X-783100Y-523767D01*
X-783683Y-524117D01*
X-785767D01*
G01X-783683D02*
X-782433Y-527500D01*
G01X-777300D02*
Y-524350D01*
X-778967Y-520500D01*
G01X-775633D02*
X-777300Y-524350D01*
G01X-765367Y-527500D02*
Y-520500D01*
X-763367D01*
X-762700Y-520850D01*
X-762200Y-521667D01*
X-762033Y-522600D01*
X-762200Y-523533D01*
X-762617Y-524233D01*
X-763367Y-524584D01*
X-765367D01*
G01X-758567Y-527500D02*
Y-520500D01*
X-756483D01*
X-755817Y-520850D01*
X-755400Y-521317D01*
X-755233Y-522250D01*
X-755400Y-523183D01*
X-755900Y-523767D01*
X-756483Y-524117D01*
X-758567D01*
G01X-756483D02*
X-755233Y-527500D01*
G01X-750100D02*
X-750767Y-527383D01*
X-751350Y-526917D01*
X-751850Y-526217D01*
X-752183Y-525400D01*
X-752350Y-524467D01*
Y-523533D01*
X-752183Y-522600D01*
X-751850Y-521783D01*
X-751350Y-521083D01*
X-750767Y-520617D01*
X-750100Y-520500D01*
X-749433Y-520617D01*
X-748850Y-521083D01*
X-748350Y-521783D01*
X-748017Y-522600D01*
X-747850Y-523533D01*
Y-524467D01*
X-748017Y-525400D01*
X-748350Y-526217D01*
X-748850Y-526917D01*
X-749433Y-527383D01*
X-750100Y-527500D01*
G01X-744967D02*
Y-520500D01*
X-742967D01*
X-742300Y-520850D01*
X-741800Y-521667D01*
X-741633Y-522600D01*
X-741800Y-523533D01*
X-742217Y-524233D01*
X-742967Y-524584D01*
X-744967D01*
G01X-734833Y-527500D02*
X-738167D01*
Y-520500D01*
X-734833D01*
G01X-736167Y-523883D02*
X-738167D01*
G01X-731367Y-527500D02*
Y-520500D01*
X-729283D01*
X-728617Y-520850D01*
X-728200Y-521317D01*
X-728033Y-522250D01*
X-728200Y-523183D01*
X-728700Y-523767D01*
X-729283Y-524117D01*
X-731367D01*
G01X-729283D02*
X-728033Y-527500D01*
G01X-722900Y-520500D02*
Y-527500D01*
G01X-724817Y-520500D02*
X-720983D01*
G01X-716100Y-527500D02*
Y-524350D01*
X-717767Y-520500D01*
G01X-714433D02*
X-716100Y-524350D01*
G01X-702500Y-527500D02*
X-703167Y-527383D01*
X-703750Y-526917D01*
X-704250Y-526217D01*
X-704583Y-525400D01*
X-704750Y-524467D01*
Y-523533D01*
X-704583Y-522600D01*
X-704250Y-521783D01*
X-703750Y-521083D01*
X-703167Y-520617D01*
X-702500Y-520500D01*
X-701833Y-520617D01*
X-701250Y-521083D01*
X-700750Y-521783D01*
X-700417Y-522600D01*
X-700250Y-523533D01*
Y-524467D01*
X-700417Y-525400D01*
X-700750Y-526217D01*
X-701250Y-526917D01*
X-701833Y-527383D01*
X-702500Y-527500D01*
G01X-697283D02*
Y-520500D01*
X-694117D01*
G01X-695283Y-523883D02*
X-697283D01*
G01X-684267Y-527500D02*
Y-520500D01*
X-682100Y-526333D01*
X-679933Y-520500D01*
Y-527500D01*
G01X-676300Y-520500D02*
X-674300D01*
G01X-675300D02*
Y-527500D01*
G01X-676300D02*
X-674300D01*
G01X-666667Y-521083D02*
X-667167Y-520733D01*
X-667750Y-520500D01*
X-668417D01*
X-669167Y-520850D01*
X-669750Y-521433D01*
X-670167Y-522133D01*
X-670500Y-523300D01*
X-670583Y-524350D01*
X-670417Y-525400D01*
X-670167Y-526100D01*
X-669667Y-526800D01*
X-669083Y-527267D01*
X-668500Y-527500D01*
X-667917D01*
X-667333Y-527267D01*
X-666833Y-526917D01*
X-666417Y-526450D01*
G01X-663367Y-527500D02*
Y-520500D01*
X-661283D01*
X-660617Y-520850D01*
X-660200Y-521317D01*
X-660033Y-522250D01*
X-660200Y-523183D01*
X-660700Y-523767D01*
X-661283Y-524117D01*
X-663367D01*
G01X-661283D02*
X-660033Y-527500D01*
G01X-654900D02*
X-655567Y-527383D01*
X-656150Y-526917D01*
X-656650Y-526217D01*
X-656983Y-525400D01*
X-657150Y-524467D01*
Y-523533D01*
X-656983Y-522600D01*
X-656650Y-521783D01*
X-656150Y-521083D01*
X-655567Y-520617D01*
X-654900Y-520500D01*
X-654233Y-520617D01*
X-653650Y-521083D01*
X-653150Y-521783D01*
X-652817Y-522600D01*
X-652650Y-523533D01*
Y-524467D01*
X-652817Y-525400D01*
X-653150Y-526217D01*
X-653650Y-526917D01*
X-654233Y-527383D01*
X-654900Y-527500D01*
G01X-649850Y-526567D02*
X-649183Y-527150D01*
X-648433Y-527500D01*
X-647767D01*
X-647100Y-527150D01*
X-646600Y-526567D01*
X-646350Y-525750D01*
X-646517Y-524933D01*
X-646933Y-524233D01*
X-647683Y-523767D01*
X-648683Y-523533D01*
X-649267Y-523067D01*
X-649517Y-522250D01*
X-649350Y-521433D01*
X-648933Y-520850D01*
X-648350Y-520500D01*
X-647767D01*
X-647183Y-520733D01*
X-646683Y-521317D01*
G01X-641300Y-527500D02*
X-641967Y-527383D01*
X-642550Y-526917D01*
X-643050Y-526217D01*
X-643383Y-525400D01*
X-643550Y-524467D01*
Y-523533D01*
X-643383Y-522600D01*
X-643050Y-521783D01*
X-642550Y-521083D01*
X-641967Y-520617D01*
X-641300Y-520500D01*
X-640633Y-520617D01*
X-640050Y-521083D01*
X-639550Y-521783D01*
X-639217Y-522600D01*
X-639050Y-523533D01*
Y-524467D01*
X-639217Y-525400D01*
X-639550Y-526217D01*
X-640050Y-526917D01*
X-640633Y-527383D01*
X-641300Y-527500D01*
G01X-636083D02*
Y-520500D01*
X-632917D01*
G01X-634083Y-523883D02*
X-636083D01*
G01X-627700Y-520500D02*
Y-527500D01*
G01X-629617Y-520500D02*
X-625783D01*
G01X-872500Y-505500D02*
Y-512500D01*
G01X-874417Y-505500D02*
X-870583D01*
G01X-867450Y-512500D02*
Y-505500D01*
G01X-863950D02*
Y-512500D01*
G01Y-509000D02*
X-867450D01*
G01X-859900Y-505500D02*
X-857900D01*
G01X-858900D02*
Y-512500D01*
G01X-859900D02*
X-857900D01*
G01X-853850Y-511567D02*
X-853183Y-512150D01*
X-852433Y-512500D01*
X-851767D01*
X-851100Y-512150D01*
X-850600Y-511567D01*
X-850350Y-510750D01*
X-850517Y-509933D01*
X-850933Y-509233D01*
X-851683Y-508767D01*
X-852683Y-508533D01*
X-853267Y-508067D01*
X-853517Y-507250D01*
X-853350Y-506433D01*
X-852933Y-505850D01*
X-852350Y-505500D01*
X-851767D01*
X-851183Y-505733D01*
X-850683Y-506317D01*
G01X-840333Y-512500D02*
Y-505500D01*
X-838667D01*
X-838000Y-505850D01*
X-837500Y-506317D01*
X-837083Y-507017D01*
X-836750Y-507833D01*
X-836667Y-509000D01*
X-836750Y-510167D01*
X-837083Y-510983D01*
X-837500Y-511684D01*
X-838000Y-512150D01*
X-838667Y-512500D01*
X-840333D01*
G01X-833367D02*
Y-505500D01*
X-831283D01*
X-830617Y-505850D01*
X-830200Y-506317D01*
X-830033Y-507250D01*
X-830200Y-508183D01*
X-830700Y-508767D01*
X-831283Y-509117D01*
X-833367D01*
G01X-831283D02*
X-830033Y-512500D01*
G01X-826983D02*
X-824900Y-505500D01*
X-822817Y-512500D01*
G01X-823567Y-510050D02*
X-826233D01*
G01X-820600Y-505500D02*
X-819433Y-512500D01*
X-818100Y-505500D01*
X-816767Y-512500D01*
X-815600Y-505500D01*
G01X-812300D02*
X-810300D01*
G01X-811300D02*
Y-512500D01*
G01X-812300D02*
X-810300D01*
G01X-806417D02*
Y-505500D01*
X-802583Y-512500D01*
Y-505500D01*
G01X-797200Y-509000D02*
X-795533D01*
Y-511100D01*
X-796033Y-511800D01*
X-796617Y-512267D01*
X-797450Y-512500D01*
X-798283Y-512267D01*
X-798867Y-511800D01*
X-799367Y-511100D01*
X-799700Y-510283D01*
X-799867Y-509350D01*
Y-508533D01*
X-799700Y-507833D01*
X-799367Y-507017D01*
X-798867Y-506317D01*
X-798367Y-505850D01*
X-797700Y-505500D01*
X-797117D01*
X-796450Y-505733D01*
X-795950Y-506200D01*
G01X-782267Y-506083D02*
X-782767Y-505733D01*
X-783350Y-505500D01*
X-784017D01*
X-784767Y-505850D01*
X-785350Y-506433D01*
X-785767Y-507133D01*
X-786100Y-508300D01*
X-786183Y-509350D01*
X-786017Y-510400D01*
X-785767Y-511100D01*
X-785267Y-511800D01*
X-784683Y-512267D01*
X-784100Y-512500D01*
X-783517D01*
X-782933Y-512267D01*
X-782433Y-511917D01*
X-782017Y-511450D01*
G01X-777300Y-512500D02*
X-777967Y-512383D01*
X-778550Y-511917D01*
X-779050Y-511217D01*
X-779383Y-510400D01*
X-779550Y-509467D01*
Y-508533D01*
X-779383Y-507600D01*
X-779050Y-506783D01*
X-778550Y-506083D01*
X-777967Y-505617D01*
X-777300Y-505500D01*
X-776633Y-505617D01*
X-776050Y-506083D01*
X-775550Y-506783D01*
X-775217Y-507600D01*
X-775050Y-508533D01*
Y-509467D01*
X-775217Y-510400D01*
X-775550Y-511217D01*
X-776050Y-511917D01*
X-776633Y-512383D01*
X-777300Y-512500D01*
G01X-772417D02*
Y-505500D01*
X-768583Y-512500D01*
Y-505500D01*
G01X-763700D02*
Y-512500D01*
G01X-765617Y-505500D02*
X-761783D01*
G01X-758983Y-512500D02*
X-756900Y-505500D01*
X-754817Y-512500D01*
G01X-755567Y-510050D02*
X-758233D01*
G01X-751100Y-505500D02*
X-749100D01*
G01X-750100D02*
Y-512500D01*
G01X-751100D02*
X-749100D01*
G01X-745217D02*
Y-505500D01*
X-741383Y-512500D01*
Y-505500D01*
G01X-738250Y-511567D02*
X-737583Y-512150D01*
X-736833Y-512500D01*
X-736167D01*
X-735500Y-512150D01*
X-735000Y-511567D01*
X-734750Y-510750D01*
X-734917Y-509933D01*
X-735333Y-509233D01*
X-736083Y-508767D01*
X-737083Y-508533D01*
X-737667Y-508067D01*
X-737917Y-507250D01*
X-737750Y-506433D01*
X-737333Y-505850D01*
X-736750Y-505500D01*
X-736167D01*
X-735583Y-505733D01*
X-735083Y-506317D01*
G01X-723900Y-505500D02*
X-721900D01*
G01X-722900D02*
Y-512500D01*
G01X-723900D02*
X-721900D01*
G01X-718017D02*
Y-505500D01*
X-714183Y-512500D01*
Y-505500D01*
G01X-710883Y-512500D02*
Y-505500D01*
X-707717D01*
G01X-708883Y-508883D02*
X-710883D01*
G01X-702500Y-512500D02*
X-703167Y-512383D01*
X-703750Y-511917D01*
X-704250Y-511217D01*
X-704583Y-510400D01*
X-704750Y-509467D01*
Y-508533D01*
X-704583Y-507600D01*
X-704250Y-506783D01*
X-703750Y-506083D01*
X-703167Y-505617D01*
X-702500Y-505500D01*
X-701833Y-505617D01*
X-701250Y-506083D01*
X-700750Y-506783D01*
X-700417Y-507600D01*
X-700250Y-508533D01*
Y-509467D01*
X-700417Y-510400D01*
X-700750Y-511217D01*
X-701250Y-511917D01*
X-701833Y-512383D01*
X-702500Y-512500D01*
G01X-697367D02*
Y-505500D01*
X-695283D01*
X-694617Y-505850D01*
X-694200Y-506317D01*
X-694033Y-507250D01*
X-694200Y-508183D01*
X-694700Y-508767D01*
X-695283Y-509117D01*
X-697367D01*
G01X-695283D02*
X-694033Y-512500D01*
G01X-691067D02*
Y-505500D01*
X-688900Y-511333D01*
X-686733Y-505500D01*
Y-512500D01*
G01X-684183D02*
X-682100Y-505500D01*
X-680017Y-512500D01*
G01X-680767Y-510050D02*
X-683433D01*
G01X-675300Y-505500D02*
Y-512500D01*
G01X-677217Y-505500D02*
X-673383D01*
G01X-669500D02*
X-667500D01*
G01X-668500D02*
Y-512500D01*
G01X-669500D02*
X-667500D01*
G01X-661700D02*
X-662367Y-512383D01*
X-662950Y-511917D01*
X-663450Y-511217D01*
X-663783Y-510400D01*
X-663950Y-509467D01*
Y-508533D01*
X-663783Y-507600D01*
X-663450Y-506783D01*
X-662950Y-506083D01*
X-662367Y-505617D01*
X-661700Y-505500D01*
X-661033Y-505617D01*
X-660450Y-506083D01*
X-659950Y-506783D01*
X-659617Y-507600D01*
X-659450Y-508533D01*
Y-509467D01*
X-659617Y-510400D01*
X-659950Y-511217D01*
X-660450Y-511917D01*
X-661033Y-512383D01*
X-661700Y-512500D01*
G01X-656817D02*
Y-505500D01*
X-652983Y-512500D01*
Y-505500D01*
G01X-643800D02*
X-642633Y-512500D01*
X-641300Y-505500D01*
X-639967Y-512500D01*
X-638800Y-505500D01*
G01X-636250Y-512500D02*
Y-505500D01*
G01X-632750D02*
Y-512500D01*
G01Y-509000D02*
X-636250D01*
G01X-628700Y-505500D02*
X-626700D01*
G01X-627700D02*
Y-512500D01*
G01X-628700D02*
X-626700D01*
G01X-619067Y-506083D02*
X-619567Y-505733D01*
X-620150Y-505500D01*
X-620817D01*
X-621567Y-505850D01*
X-622150Y-506433D01*
X-622567Y-507133D01*
X-622900Y-508300D01*
X-622983Y-509350D01*
X-622817Y-510400D01*
X-622567Y-511100D01*
X-622067Y-511800D01*
X-621483Y-512267D01*
X-620900Y-512500D01*
X-620317D01*
X-619733Y-512267D01*
X-619233Y-511917D01*
X-618817Y-511450D01*
G01X-615850Y-512500D02*
Y-505500D01*
G01X-612350D02*
Y-512500D01*
G01Y-509000D02*
X-615850D01*
G01X-601500Y-505500D02*
X-599500D01*
G01X-600500D02*
Y-512500D01*
G01X-601500D02*
X-599500D01*
G01X-595450Y-511567D02*
X-594783Y-512150D01*
X-594033Y-512500D01*
X-593367D01*
X-592700Y-512150D01*
X-592200Y-511567D01*
X-591950Y-510750D01*
X-592117Y-509933D01*
X-592533Y-509233D01*
X-593283Y-508767D01*
X-594283Y-508533D01*
X-594867Y-508067D01*
X-595117Y-507250D01*
X-594950Y-506433D01*
X-594533Y-505850D01*
X-593950Y-505500D01*
X-593367D01*
X-592783Y-505733D01*
X-592283Y-506317D01*
G01X-858133Y-452500D02*
Y-445500D01*
X-856467D01*
X-855800Y-445850D01*
X-855300Y-446317D01*
X-854883Y-447017D01*
X-854550Y-447833D01*
X-854467Y-449000D01*
X-854550Y-450167D01*
X-854883Y-450983D01*
X-855300Y-451684D01*
X-855800Y-452150D01*
X-856467Y-452500D01*
X-858133D01*
G01X-847833D02*
X-851167D01*
Y-445500D01*
X-847833D01*
G01X-849167Y-448883D02*
X-851167D01*
G01X-844450Y-451567D02*
X-843783Y-452150D01*
X-843033Y-452500D01*
X-842367D01*
X-841700Y-452150D01*
X-841200Y-451567D01*
X-840950Y-450750D01*
X-841117Y-449933D01*
X-841533Y-449233D01*
X-842283Y-448767D01*
X-843283Y-448533D01*
X-843867Y-448067D01*
X-844117Y-447250D01*
X-843950Y-446433D01*
X-843533Y-445850D01*
X-842950Y-445500D01*
X-842367D01*
X-841783Y-445733D01*
X-841283Y-446317D01*
G01X-836900Y-445500D02*
X-834900D01*
G01X-835900D02*
Y-452500D01*
G01X-836900D02*
X-834900D01*
G01X-828600Y-449000D02*
X-826933D01*
Y-451100D01*
X-827433Y-451800D01*
X-828017Y-452267D01*
X-828850Y-452500D01*
X-829683Y-452267D01*
X-830267Y-451800D01*
X-830767Y-451100D01*
X-831100Y-450283D01*
X-831267Y-449350D01*
Y-448533D01*
X-831100Y-447833D01*
X-830767Y-447017D01*
X-830267Y-446317D01*
X-829767Y-445850D01*
X-829100Y-445500D01*
X-828517D01*
X-827850Y-445733D01*
X-827350Y-446200D01*
G01X-824217Y-452500D02*
Y-445500D01*
X-820383Y-452500D01*
Y-445500D01*
G01X-813833Y-452500D02*
X-817167D01*
Y-445500D01*
X-813833D01*
G01X-815167Y-448883D02*
X-817167D01*
G01X-810367Y-452500D02*
Y-445500D01*
X-808283D01*
X-807617Y-445850D01*
X-807200Y-446317D01*
X-807033Y-447250D01*
X-807200Y-448183D01*
X-807700Y-448767D01*
X-808283Y-449117D01*
X-810367D01*
G01X-808283D02*
X-807033Y-452500D01*
G01X-858133D02*
Y-445500D01*
X-856467D01*
X-855800Y-445850D01*
X-855300Y-446317D01*
X-854883Y-447017D01*
X-854550Y-447833D01*
X-854467Y-449000D01*
X-854550Y-450167D01*
X-854883Y-450983D01*
X-855300Y-451684D01*
X-855800Y-452150D01*
X-856467Y-452500D01*
X-858133D01*
G01X-847833D02*
X-851167D01*
Y-445500D01*
X-847833D01*
G01X-849167Y-448883D02*
X-851167D01*
G01X-844450Y-451567D02*
X-843783Y-452150D01*
X-843033Y-452500D01*
X-842367D01*
X-841700Y-452150D01*
X-841200Y-451567D01*
X-840950Y-450750D01*
X-841117Y-449933D01*
X-841533Y-449233D01*
X-842283Y-448767D01*
X-843283Y-448533D01*
X-843867Y-448067D01*
X-844117Y-447250D01*
X-843950Y-446433D01*
X-843533Y-445850D01*
X-842950Y-445500D01*
X-842367D01*
X-841783Y-445733D01*
X-841283Y-446317D01*
G01X-836900Y-445500D02*
X-834900D01*
G01X-835900D02*
Y-452500D01*
G01X-836900D02*
X-834900D01*
G01X-828600Y-449000D02*
X-826933D01*
Y-451100D01*
X-827433Y-451800D01*
X-828017Y-452267D01*
X-828850Y-452500D01*
X-829683Y-452267D01*
X-830267Y-451800D01*
X-830767Y-451100D01*
X-831100Y-450283D01*
X-831267Y-449350D01*
Y-448533D01*
X-831100Y-447833D01*
X-830767Y-447017D01*
X-830267Y-446317D01*
X-829767Y-445850D01*
X-829100Y-445500D01*
X-828517D01*
X-827850Y-445733D01*
X-827350Y-446200D01*
G01X-824217Y-452500D02*
Y-445500D01*
X-820383Y-452500D01*
Y-445500D01*
G01X-813833Y-452500D02*
X-817167D01*
Y-445500D01*
X-813833D01*
G01X-815167Y-448883D02*
X-817167D01*
G01X-810367Y-452500D02*
Y-445500D01*
X-808283D01*
X-807617Y-445850D01*
X-807200Y-446317D01*
X-807033Y-447250D01*
X-807200Y-448183D01*
X-807700Y-448767D01*
X-808283Y-449117D01*
X-810367D01*
G01X-808283D02*
X-807033Y-452500D01*
G01X-642033Y-455000D02*
Y-448000D01*
X-640367D01*
X-639700Y-448350D01*
X-639200Y-448817D01*
X-638783Y-449517D01*
X-638450Y-450333D01*
X-638367Y-451500D01*
X-638450Y-452667D01*
X-638783Y-453483D01*
X-639200Y-454184D01*
X-639700Y-454650D01*
X-640367Y-455000D01*
X-642033D01*
G01X-635483D02*
X-633400Y-448000D01*
X-631317Y-455000D01*
G01X-632067Y-452550D02*
X-634733D01*
G01X-626600Y-448000D02*
Y-455000D01*
G01X-628517Y-448000D02*
X-624683D01*
G01X-618133Y-455000D02*
X-621467D01*
Y-448000D01*
X-618133D01*
G01X-619467Y-451383D02*
X-621467D01*
G54D18*
G01X-1020800Y-457700D02*
G02X-1020300Y-458200I0J-500D01*
G01Y-458400D01*
G02X-1020900Y-459000I-600J0D01*
G01X-1021300D01*
G01X-1021800Y-460500D02*
Y-457700D01*
X-1020600D01*
G01X-1018340Y-459100D02*
G03I-2660J0D01*
G01X-1020700D02*
X-1020200Y-460500D01*
M02*
